G04 ================== begin FILE IDENTIFICATION RECORD ==================*
G04 Layout Name:  13130-1b.brd*
G04 Film Name:    L11GND*
G04 File Format:  Gerber RS274X*
G04 File Origin:  Cadence Allegro 16.5-S037*
G04 Origin Date:  Thu Nov 13 17:27:20 2014*
G04 *
G04 Layer:  VIA CLASS/L11GND*
G04 Layer:  PIN/L11GND*
G04 Layer:  ETCH/L11GND*
G04 Layer:  DRAWING FORMAT/LAYER_PCB_STORY*
G04 Layer:  DRAWING FORMAT/LAYER_L11GND*
G04 *
G04 Offset:    (0.00 0.00)*
G04 Mirror:    No*
G04 Mode:      Negative*
G04 Rotation:  0*
G04 FullContactRelief:  No*
G04 UndefLineWidth:     6.00*
G04 ================== end FILE IDENTIFICATION RECORD ====================*
%FSLAX35Y35*MOIN*%
%IR0*IPPOS*OFA0.00000B0.00000*MIA0B0*SFA1.00000B1.00000*%
%ADD15C,.03*%
%ADD20C,.032*%
%ADD18C,.072*%
%ADD13C,.036*%
%ADD24C,.028*%
%ADD22C,.091*%
%ADD17C,.093*%
%ADD19C,.068*%
%AMMACRO23*
4,1,15,.00398,.00044,
.003999,.000208,
.004004,-.000025,
.003996,-.000258,
.00398,-.00044,
.00483,-.00129,
.004897,-.001007,
.004947,-.000721,
.004981,-.000432,
.004997,-.000141,
.004997,.000149,
.00498,.00044,
.004946,.000729,
.004895,.001015,
.00483,.00129,
.00398,.00044,
45.*
4,1,15,.00044,-.00398,
.000208,-.003999,
-.000025,-.004004,
-.000258,-.003996,
-.00044,-.00398,
-.00129,-.00483,
-.001007,-.004897,
-.000721,-.004947,
-.000432,-.004981,
-.000141,-.004997,
.000149,-.004997,
.00044,-.00498,
.000729,-.004946,
.001015,-.004895,
.00129,-.00483,
.00044,-.00398,
45.*
4,1,15,-.00398,-.00044,
-.003999,-.000208,
-.004004,.000025,
-.003996,.000258,
-.00398,.00044,
-.00483,.00129,
-.004897,.001007,
-.004947,.000721,
-.004981,.000432,
-.004997,.000141,
-.004997,-.000149,
-.00498,-.00044,
-.004946,-.000729,
-.004895,-.001015,
-.00483,-.00129,
-.00398,-.00044,
45.*
4,1,15,-.00044,.00398,
-.000208,.003999,
.000025,.004004,
.000258,.003996,
.00044,.00398,
.00129,.00483,
.001007,.004897,
.000721,.004947,
.000432,.004981,
.000141,.004997,
-.000149,.004997,
-.00044,.00498,
-.000729,.004946,
-.001015,.004895,
-.00129,.00483,
-.00044,.00398,
45.*
%
%ADD23MACRO23*%
%AMMACRO14*
4,1,15,.00398,.00044,
.003999,.000208,
.004004,-.000025,
.003996,-.000258,
.00398,-.00044,
.00483,-.00129,
.004897,-.001007,
.004947,-.000721,
.004981,-.000432,
.004997,-.000141,
.004997,.000149,
.00498,.00044,
.004946,.000729,
.004895,.001015,
.00483,.00129,
.00398,.00044,
90.*
4,1,15,.00044,-.00398,
.000208,-.003999,
-.000025,-.004004,
-.000258,-.003996,
-.00044,-.00398,
-.00129,-.00483,
-.001007,-.004897,
-.000721,-.004947,
-.000432,-.004981,
-.000141,-.004997,
.000149,-.004997,
.00044,-.00498,
.000729,-.004946,
.001015,-.004895,
.00129,-.00483,
.00044,-.00398,
90.*
4,1,15,-.00398,-.00044,
-.003999,-.000208,
-.004004,.000025,
-.003996,.000258,
-.00398,.00044,
-.00483,.00129,
-.004897,.001007,
-.004947,.000721,
-.004981,.000432,
-.004997,.000141,
-.004997,-.000149,
-.00498,-.00044,
-.004946,-.000729,
-.004895,-.001015,
-.00483,-.00129,
-.00398,-.00044,
90.*
4,1,15,-.00044,.00398,
-.000208,.003999,
.000025,.004004,
.000258,.003996,
.00044,.00398,
.00129,.00483,
.001007,.004897,
.000721,.004947,
.000432,.004981,
.000141,.004997,
-.000149,.004997,
-.00044,.00498,
-.000729,.004946,
-.001015,.004895,
-.00129,.00483,
-.00044,.00398,
90.*
%
%ADD14MACRO14*%
%AMMACRO12*
4,1,15,.00398,.00044,
.003999,.000208,
.004004,-.000025,
.003996,-.000258,
.00398,-.00044,
.00483,-.00129,
.004897,-.001007,
.004947,-.000721,
.004981,-.000432,
.004997,-.000141,
.004997,.000149,
.00498,.00044,
.004946,.000729,
.004895,.001015,
.00483,.00129,
.00398,.00044,
0.0*
4,1,15,.00044,-.00398,
.000208,-.003999,
-.000025,-.004004,
-.000258,-.003996,
-.00044,-.00398,
-.00129,-.00483,
-.001007,-.004897,
-.000721,-.004947,
-.000432,-.004981,
-.000141,-.004997,
.000149,-.004997,
.00044,-.00498,
.000729,-.004946,
.001015,-.004895,
.00129,-.00483,
.00044,-.00398,
0.0*
4,1,15,-.00398,-.00044,
-.003999,-.000208,
-.004004,.000025,
-.003996,.000258,
-.00398,.00044,
-.00483,.00129,
-.004897,.001007,
-.004947,.000721,
-.004981,.000432,
-.004997,.000141,
-.004997,-.000149,
-.00498,-.00044,
-.004946,-.000729,
-.004895,-.001015,
-.00483,-.00129,
-.00398,-.00044,
0.0*
4,1,15,-.00044,.00398,
-.000208,.003999,
.000025,.004004,
.000258,.003996,
.00044,.00398,
.00129,.00483,
.001007,.004897,
.000721,.004947,
.000432,.004981,
.000141,.004997,
-.000149,.004997,
-.00044,.00498,
-.000729,.004946,
-.001015,.004895,
-.00129,.00483,
-.00044,.00398,
0.0*
%
%ADD12MACRO12*%
%ADD29O,.217X.154*%
%ADD11C,.114*%
%ADD16C,.154*%
%ADD21C,.147*%
%ADD10C,.168*%
%AMMACRO28*
4,1,15,.00398,.00044,
.003999,.000208,
.004004,-.000025,
.003996,-.000258,
.00398,-.00044,
.00483,-.00129,
.004897,-.001007,
.004947,-.000721,
.004981,-.000432,
.004997,-.000141,
.004997,.000149,
.00498,.00044,
.004946,.000729,
.004895,.001015,
.00483,.00129,
.00398,.00044,
315.*
4,1,15,.00044,-.00398,
.000208,-.003999,
-.000025,-.004004,
-.000258,-.003996,
-.00044,-.00398,
-.00129,-.00483,
-.001007,-.004897,
-.000721,-.004947,
-.000432,-.004981,
-.000141,-.004997,
.000149,-.004997,
.00044,-.00498,
.000729,-.004946,
.001015,-.004895,
.00129,-.00483,
.00044,-.00398,
315.*
4,1,15,-.00398,-.00044,
-.003999,-.000208,
-.004004,.000025,
-.003996,.000258,
-.00398,.00044,
-.00483,.00129,
-.004897,.001007,
-.004947,.000721,
-.004981,.000432,
-.004997,.000141,
-.004997,-.000149,
-.00498,-.00044,
-.004946,-.000729,
-.004895,-.001015,
-.00483,-.00129,
-.00398,-.00044,
315.*
4,1,15,-.00044,.00398,
-.000208,.003999,
.000025,.004004,
.000258,.003996,
.00044,.00398,
.00129,.00483,
.001007,.004897,
.000721,.004947,
.000432,.004981,
.000141,.004997,
-.000149,.004997,
-.00044,.00498,
-.000729,.004946,
-.001015,.004895,
-.00129,.00483,
-.00044,.00398,
315.*
%
%ADD28MACRO28*%
%AMMACRO27*
4,1,15,.00398,.00044,
.003999,.000208,
.004004,-.000025,
.003996,-.000258,
.00398,-.00044,
.00483,-.00129,
.004897,-.001007,
.004947,-.000721,
.004981,-.000432,
.004997,-.000141,
.004997,.000149,
.00498,.00044,
.004946,.000729,
.004895,.001015,
.00483,.00129,
.00398,.00044,
180.*
4,1,15,.00044,-.00398,
.000208,-.003999,
-.000025,-.004004,
-.000258,-.003996,
-.00044,-.00398,
-.00129,-.00483,
-.001007,-.004897,
-.000721,-.004947,
-.000432,-.004981,
-.000141,-.004997,
.000149,-.004997,
.00044,-.00498,
.000729,-.004946,
.001015,-.004895,
.00129,-.00483,
.00044,-.00398,
180.*
4,1,15,-.00398,-.00044,
-.003999,-.000208,
-.004004,.000025,
-.003996,.000258,
-.00398,.00044,
-.00483,.00129,
-.004897,.001007,
-.004947,.000721,
-.004981,.000432,
-.004997,.000141,
-.004997,-.000149,
-.00498,-.00044,
-.004946,-.000729,
-.004895,-.001015,
-.00483,-.00129,
-.00398,-.00044,
180.*
4,1,15,-.00044,.00398,
-.000208,.003999,
.000025,.004004,
.000258,.003996,
.00044,.00398,
.00129,.00483,
.001007,.004897,
.000721,.004947,
.000432,.004981,
.000141,.004997,
-.000149,.004997,
-.00044,.00498,
-.000729,.004946,
-.001015,.004895,
-.00129,.00483,
-.00044,.00398,
180.*
%
%ADD27MACRO27*%
%AMMACRO26*
4,1,15,.00398,.00044,
.003999,.000208,
.004004,-.000025,
.003996,-.000258,
.00398,-.00044,
.00483,-.00129,
.004897,-.001007,
.004947,-.000721,
.004981,-.000432,
.004997,-.000141,
.004997,.000149,
.00498,.00044,
.004946,.000729,
.004895,.001015,
.00483,.00129,
.00398,.00044,
270.*
4,1,15,.00044,-.00398,
.000208,-.003999,
-.000025,-.004004,
-.000258,-.003996,
-.00044,-.00398,
-.00129,-.00483,
-.001007,-.004897,
-.000721,-.004947,
-.000432,-.004981,
-.000141,-.004997,
.000149,-.004997,
.00044,-.00498,
.000729,-.004946,
.001015,-.004895,
.00129,-.00483,
.00044,-.00398,
270.*
4,1,15,-.00398,-.00044,
-.003999,-.000208,
-.004004,.000025,
-.003996,.000258,
-.00398,.00044,
-.00483,.00129,
-.004897,.001007,
-.004947,.000721,
-.004981,.000432,
-.004997,.000141,
-.004997,-.000149,
-.00498,-.00044,
-.004946,-.000729,
-.004895,-.001015,
-.00483,-.00129,
-.00398,-.00044,
270.*
4,1,15,-.00044,.00398,
-.000208,.003999,
.000025,.004004,
.000258,.003996,
.00044,.00398,
.00129,.00483,
.001007,.004897,
.000721,.004947,
.000432,.004981,
.000141,.004997,
-.000149,.004997,
-.00044,.00498,
-.000729,.004946,
-.001015,.004895,
-.00129,.00483,
-.00044,.00398,
270.*
%
%ADD26MACRO26*%
%AMMACRO25*
4,1,15,.00398,.00044,
.003999,.000208,
.004004,-.000025,
.003996,-.000258,
.00398,-.00044,
.00483,-.00129,
.004897,-.001007,
.004947,-.000721,
.004981,-.000432,
.004997,-.000141,
.004997,.000149,
.00498,.00044,
.004946,.000729,
.004895,.001015,
.00483,.00129,
.00398,.00044,
135.*
4,1,15,.00044,-.00398,
.000208,-.003999,
-.000025,-.004004,
-.000258,-.003996,
-.00044,-.00398,
-.00129,-.00483,
-.001007,-.004897,
-.000721,-.004947,
-.000432,-.004981,
-.000141,-.004997,
.000149,-.004997,
.00044,-.00498,
.000729,-.004946,
.001015,-.004895,
.00129,-.00483,
.00044,-.00398,
135.*
4,1,15,-.00398,-.00044,
-.003999,-.000208,
-.004004,.000025,
-.003996,.000258,
-.00398,.00044,
-.00483,.00129,
-.004897,.001007,
-.004947,.000721,
-.004981,.000432,
-.004997,.000141,
-.004997,-.000149,
-.00498,-.00044,
-.004946,-.000729,
-.004895,-.001015,
-.00483,-.00129,
-.00398,-.00044,
135.*
4,1,15,-.00044,.00398,
-.000208,.003999,
.000025,.004004,
.000258,.003996,
.00044,.00398,
.00129,.00483,
.001007,.004897,
.000721,.004947,
.000432,.004981,
.000141,.004997,
-.000149,.004997,
-.00044,.00498,
-.000729,.004946,
-.001015,.004895,
-.00129,.00483,
-.00044,.00398,
135.*
%
%ADD25MACRO25*%
%ADD30C,.02*%
%ADD31C,.006*%
%ADD40C,.03004*%
%ADD37C,.06404*%
%ADD36C,.06804*%
%ADD38C,.08704*%
%ADD35C,.08904*%
%ADD39C,.09176*%
%ADD32O,.21302X.15002*%
%ADD33C,.11004*%
%ADD34C,.15004*%
G75*
%LPD*%
G75*
G36*
G01X-6000Y-6000D02*
X832773D01*
Y296551D01*
X-6000D01*
Y-6000D01*
G37*
%LPC*%
G75*
G36*
G01X417323Y3004D02*
G02X416390Y3937I0J933D01*
G01Y42126D01*
G03X409449Y49067I-6941J0D01*
G01X393701D01*
G03X386760Y42126I0J-6941D01*
G01Y20648D01*
X357120D01*
Y32654D01*
X354298D01*
Y20648D01*
X353184D01*
Y32654D01*
X350360D01*
Y20648D01*
X348673D01*
Y39961D01*
G03X335185I-6744J0D01*
G01Y20648D01*
X325624D01*
Y32654D01*
X322800D01*
Y20648D01*
X321686D01*
Y32654D01*
X318864D01*
Y20648D01*
X309876D01*
Y32654D01*
X307052D01*
Y20648D01*
X305938D01*
Y32654D01*
X303116D01*
Y20648D01*
X294128D01*
Y32654D01*
X291304D01*
Y20648D01*
X290190D01*
Y32654D01*
X287368D01*
Y20648D01*
X278380D01*
Y32654D01*
X275556D01*
Y20648D01*
X274442D01*
Y32654D01*
X271620D01*
Y20648D01*
X262632D01*
Y32654D01*
X259808D01*
Y20648D01*
X258694D01*
Y32654D01*
X255872D01*
Y20648D01*
X246884D01*
Y32654D01*
X244060D01*
Y20648D01*
X242946D01*
Y32654D01*
X240124D01*
Y20648D01*
X199640D01*
Y32654D01*
X196816D01*
Y20648D01*
X195702D01*
Y32654D01*
X192880D01*
Y20648D01*
X183892D01*
Y32654D01*
X181068D01*
Y20648D01*
X179954D01*
Y32654D01*
X177132D01*
Y20648D01*
X168144D01*
Y32654D01*
X165320D01*
Y20648D01*
X164206D01*
Y32654D01*
X161384D01*
Y20648D01*
X152396D01*
Y32654D01*
X149572D01*
Y20648D01*
X148458D01*
Y32654D01*
X145636D01*
Y20648D01*
X136648D01*
Y32654D01*
X133824D01*
Y20648D01*
X132710D01*
Y32654D01*
X129888D01*
Y20648D01*
X120900D01*
Y32654D01*
X118076D01*
Y20648D01*
X116962D01*
Y32654D01*
X114140D01*
Y20648D01*
X105152D01*
Y32654D01*
X102328D01*
Y20648D01*
X101214D01*
Y32654D01*
X98392D01*
Y20648D01*
X89404D01*
Y32654D01*
X86580D01*
Y20648D01*
X85466D01*
Y32654D01*
X82644D01*
Y20648D01*
X73656D01*
Y32654D01*
X70832D01*
Y20648D01*
X69718D01*
Y32654D01*
X66896D01*
Y20648D01*
X60878D01*
Y53937D01*
G03X53937Y60878I-6941J0D01*
G01X3937D01*
G02X3004Y61811I0J933D01*
G01Y286614D01*
G02X3937Y287547I933J0D01*
G01X88250D01*
Y282189D01*
X91689Y278750D01*
X166189D01*
X181189Y263750D01*
X211689D01*
X213750Y261689D01*
Y251189D01*
X215689Y249250D01*
X258811D01*
X265311Y255750D01*
X311811D01*
X314811Y258750D01*
X323189D01*
X326189Y255750D01*
X358189D01*
X365689Y248250D01*
X405689D01*
X406750Y247189D01*
Y245811D01*
X406189Y245250D01*
X404689D01*
X388189Y228750D01*
X369689D01*
X363250Y222311D01*
Y218811D01*
X361750Y217311D01*
Y155189D01*
X363689Y153250D01*
X372811D01*
X374032Y154471D01*
X374129Y154459D01*
G03X375641Y155971I171J1341D01*
G01X375629Y156068D01*
X376311Y156750D01*
X378811D01*
X382311Y160250D01*
X384311D01*
X386811Y162750D01*
X394811D01*
X398250Y166189D01*
Y175900D01*
X421903D01*
X422046Y175852D01*
X422142Y175900D01*
X422249D01*
X422355Y176007D01*
X423142Y176400D01*
X427749D01*
X429749Y178400D01*
X449251D01*
X450251Y177400D01*
X460749D01*
X461099Y177750D01*
X465619D01*
X465672Y177634D01*
G03X468128I1228J566D01*
G01X468181Y177750D01*
X469119D01*
X469172Y177634D01*
G03X471628I1228J566D01*
G01X471681Y177750D01*
X472619D01*
X472672Y177634D01*
G03X475128I1228J566D01*
G01X475181Y177750D01*
X596811D01*
X598192Y179131D01*
X598328Y179043D01*
G03X600407Y181122I822J1257D01*
G01X600319Y181258D01*
X604588Y185527D01*
X604726Y185428D01*
G03X606822Y187524I874J1222D01*
G01X606723Y187662D01*
X615228Y196167D01*
X615361Y196093D01*
G03X617327Y198266I739J1308D01*
G01X621522Y202461D01*
G03X624707Y205419I1351J1739D01*
G01X624616Y205555D01*
X646750Y227689D01*
Y241311D01*
X641750Y246311D01*
Y282311D01*
X639811Y284250D01*
X585689D01*
X583750Y282311D01*
Y271311D01*
X582250Y269811D01*
Y257189D01*
X583750Y255689D01*
Y245811D01*
X581189Y243250D01*
X469689D01*
X468689Y242250D01*
X418250D01*
Y244811D01*
X417250Y245811D01*
Y254311D01*
X409811Y261750D01*
X397811D01*
X392811Y266750D01*
X392338D01*
X392286Y266788D01*
G03X389663Y266750I-1286J-1788D01*
G01X370494D01*
G03X370151Y266931I-1195J-1849D01*
G01X370115Y266946D01*
X367311Y269750D01*
X342811D01*
X337311Y275250D01*
X303117D01*
G02X302901Y275987I-1J400D01*
G03X305327Y286933I-4279J6690D01*
G02X305665Y287547I338J214D01*
G01X822835D01*
G02X823768Y286614I0J-933D01*
G01Y3937D01*
G02X822835Y3004I-933J0D01*
G01X670250D01*
Y14689D01*
X672750Y17189D01*
Y21811D01*
X670250Y24311D01*
Y40189D01*
X671811Y41750D01*
X678811D01*
X681750Y44689D01*
Y60311D01*
X623811Y118250D01*
X468811D01*
X464311Y122750D01*
X463689D01*
X463539Y122600D01*
X451249D01*
X442749Y131100D01*
X437151D01*
X435951Y129900D01*
X433106D01*
X432398Y130451D01*
X432249Y130600D01*
X432206D01*
X432172Y130626D01*
X431963Y130600D01*
X412249D01*
X409749Y133100D01*
X393751D01*
X390251Y129600D01*
X388251D01*
X386251Y127600D01*
X384251D01*
X382900Y126249D01*
Y101751D01*
X384900Y99751D01*
Y89251D01*
X386251Y87900D01*
X387751D01*
X388250Y87401D01*
Y87189D01*
X398689Y76750D01*
X426189D01*
X449189Y53750D01*
X516689D01*
X526689Y43750D01*
X610189D01*
X612250Y41689D01*
Y3004D01*
X417323D01*
G37*
G36*
G01X193514Y286932D02*
G03X206880I6683J-4255D01*
G02X207217Y287547I337J215D01*
G01X289750D01*
Y277250D01*
X231189D01*
X219189Y265250D01*
X181811D01*
X166811Y280250D01*
X92311D01*
X89750Y282811D01*
Y287547D01*
X193177D01*
G02X193514Y286932I0J-400D01*
G37*
G36*
G01X372971Y155532D02*
X372189Y154750D01*
X364311D01*
X363250Y155811D01*
Y216689D01*
X364750Y218189D01*
Y221689D01*
X370311Y227250D01*
X388811D01*
X405311Y243750D01*
X406811D01*
X408250Y245189D01*
Y247811D01*
X406311Y249750D01*
X366311D01*
X358811Y257250D01*
X326811D01*
X323811Y260250D01*
X314189D01*
X311189Y257250D01*
X264689D01*
X258189Y250750D01*
X216311D01*
X215250Y251811D01*
Y259189D01*
X231811Y275750D01*
X293189D01*
X295189Y273750D01*
X336689D01*
X341584Y268855D01*
G03X341948Y268490I2015J1646D01*
G01X341955Y268484D01*
X342189Y268250D01*
X342292D01*
X342337Y268225D01*
G03X344907Y268250I1263J2275D01*
G01X366689D01*
X369689Y265250D01*
X392189D01*
X397189Y260250D01*
X409189D01*
X415750Y253689D01*
Y245189D01*
X416750Y244189D01*
Y241811D01*
X415689Y240750D01*
X412189D01*
X398250Y226811D01*
Y226189D01*
X398400Y226039D01*
Y225372D01*
X398393Y225347D01*
G03Y224653I1307J-347D01*
G01X398400Y224628D01*
Y223751D01*
X400400Y221751D01*
Y213249D01*
X387400Y200249D01*
Y178251D01*
X389751Y175900D01*
X396750D01*
Y166811D01*
X394189Y164250D01*
X386189D01*
X383689Y161750D01*
X381689D01*
X378189Y158250D01*
X375689D01*
X374568Y157129D01*
X374471Y157141D01*
G03X372959Y155629I-171J-1341D01*
G01X372971Y155532D01*
G37*
G36*
G01X623189Y116750D02*
X680250Y59689D01*
Y45311D01*
X678189Y43250D01*
X671189D01*
X668750Y40811D01*
Y23689D01*
X671250Y21189D01*
Y17811D01*
X668750Y15311D01*
Y3004D01*
X613750D01*
Y42311D01*
X610811Y45250D01*
X527311D01*
X517311Y55250D01*
X449811D01*
X426811Y78250D01*
X399311D01*
X389311Y88250D01*
X389099D01*
X388249Y89100D01*
X386749D01*
X386100Y89749D01*
Y100249D01*
X384100Y102249D01*
Y125751D01*
X384749Y126400D01*
X386749D01*
X388749Y128400D01*
X390749D01*
X394249Y131900D01*
X409251D01*
X411751Y129400D01*
X431794D01*
X432502Y128849D01*
X432651Y128700D01*
X432694D01*
X432728Y128674D01*
X432937Y128700D01*
X436449D01*
X437649Y129900D01*
X442251D01*
X450751Y121400D01*
X463539D01*
X468189Y116750D01*
X623189D01*
G37*
G36*
G01X467752Y179250D02*
G03X466048I-852J-1050D01*
G01X460689D01*
X460250Y178811D01*
Y178600D01*
X450749D01*
X449749Y179600D01*
X429251D01*
X427251Y177600D01*
X423097D01*
X422954Y177648D01*
X422858Y177600D01*
X422751D01*
X422645Y177493D01*
X421858Y177100D01*
X397961D01*
X397811Y177250D01*
X397189D01*
X397039Y177100D01*
X390249D01*
X388600Y178749D01*
Y199751D01*
X401600Y212751D01*
Y222249D01*
X399600Y224249D01*
Y226039D01*
X412811Y239250D01*
X416311D01*
X417811Y240750D01*
X469311D01*
X470311Y241750D01*
X581811D01*
X585250Y245189D01*
Y256311D01*
X583750Y257811D01*
Y269189D01*
X585250Y270689D01*
Y281689D01*
X586311Y282750D01*
X639189D01*
X640250Y281689D01*
Y245689D01*
X645250Y240689D01*
Y228311D01*
X639188Y222249D01*
X629691Y212751D01*
X623302Y206362D01*
X623202Y206377D01*
G03X620696Y203871I-329J-2177D01*
G01X620711Y203771D01*
X615816Y198876D01*
X615760Y198863D01*
G03X614637Y197740I340J-1463D01*
G01X614624Y197685D01*
X604938Y187998D01*
X604910Y187984D01*
G03X604266Y187340I690J-1334D01*
G01X604252Y187312D01*
X598659Y181720D01*
X598619Y181705D01*
G03X597745Y180831I531J-1405D01*
G01X597730Y180791D01*
X596189Y179250D01*
X474752D01*
G03X473048I-852J-1050D01*
G01X471252D01*
G03X469548I-852J-1050D01*
G01X467752D01*
G37*
%LPD*%
G75*
G36*
G01X9110Y260712D02*
G02X6090Y260713I-1510J1D01*
G01Y264483D01*
G02X9110I1510J0D01*
G01Y260712D01*
G37*
G36*
G01X15100Y254750D02*
G02X12080Y254751I-1510J1D01*
G01Y258521D01*
G02X15100I1510J0D01*
G01Y254750D01*
G37*
G36*
G01X39410Y253999D02*
G02X36390Y254000I-1510J1D01*
G01Y257500D01*
G02X39410I1510J0D01*
G01Y253999D01*
G37*
G36*
G01X9110Y248902D02*
G02X6090I-1510J0D01*
G01Y252673D01*
G02X9110Y252672I1510J-1D01*
G01Y248902D01*
G37*
G36*
G01X36397Y246861D02*
X36381Y247035D01*
X36481Y250542D01*
X36489Y250550D01*
X36495Y250624D01*
G02X39503Y250639I1505J-123D01*
G01X39519Y250465D01*
X39419Y246957D01*
X39394Y246785D01*
G02X36397Y246861I-1494J216D01*
G37*
G36*
G01X400528Y242794D02*
G02X398368Y244905I-1090J1045D01*
G01X400768Y247314D01*
G02X402908Y245182I1070J-1066D01*
G01X400529Y242795D01*
X400528Y242794D01*
G37*
G36*
G01X15100Y242939D02*
G02X12080Y242940I-1510J1D01*
G01Y246710D01*
G02X15100I1510J0D01*
G01Y242939D01*
G37*
G36*
G01X39410Y239999D02*
G02X36390Y240000I-1510J1D01*
G01Y243500D01*
G02X39410I1510J0D01*
G01Y239999D01*
G37*
G36*
G01X390616Y239712D02*
X390725Y239846D01*
X393170Y242218D01*
X393181D01*
X393237Y242267D01*
G02X395280Y240044I991J-1139D01*
G01X395137Y239905D01*
X395143Y239898D01*
X392844Y237667D01*
X392707Y237562D01*
G02X390616Y239712I-919J1198D01*
G37*
G36*
G01X9110Y237090D02*
G02X6090Y237091I-1510J1D01*
G01Y240861D01*
G02X9110I1510J0D01*
G01Y237090D01*
G37*
G36*
G01X36397Y232861D02*
X36381Y233035D01*
X36481Y236542D01*
X36489Y236550D01*
X36495Y236624D01*
G02X39503Y236639I1505J-123D01*
G01X39519Y236465D01*
X39419Y232957D01*
X39394Y232785D01*
G02X36397Y232861I-1494J216D01*
G37*
G36*
G01X14600Y231129D02*
G02X11580I-1510J0D01*
G01Y234900D01*
G02X14600Y234899I1510J-1D01*
G01Y231129D01*
G37*
G36*
G01X39410Y225999D02*
G02X36390Y226000I-1510J1D01*
G01Y229500D01*
G02X39410I1510J0D01*
G01Y225999D01*
G37*
G36*
G01Y218999D02*
G02X36390Y219000I-1510J1D01*
G01Y222500D01*
G02X39410I1510J0D01*
G01Y218999D01*
G37*
G36*
G01X329534Y219215D02*
G02X327485Y217426I-1025J-895D01*
G01X325999Y219130D01*
G02X328049Y220918I1025J894D01*
G01X329534Y219215D01*
G37*
G36*
G01X359255Y215107D02*
X359109Y215175D01*
X357235Y216357D01*
Y216365D01*
X357154Y216425D01*
G02X358692Y218666I812J1091D01*
G01X358861Y218559D01*
X358866Y218567D01*
X360570Y217492D01*
X360694Y217389D01*
G02X359255Y215107I-867J-1048D01*
G37*
G36*
G01X338701Y215752D02*
G02X335981Y215710I-1360J-21D01*
G01X335947Y217939D01*
G02X338667Y217982I1360J22D01*
G01X338701Y215752D01*
G37*
G36*
G01X344602Y213717D02*
G02X341882Y213663I-1360J-27D01*
G01X341838Y215882D01*
G02X344558Y215937I1360J27D01*
G01X344602Y213717D01*
G37*
G36*
G01X333018Y212687D02*
G02X330298Y212634I-1360J-26D01*
G01X330256Y214834D01*
G02X332976Y214886I1360J26D01*
G01X333018Y212687D01*
G37*
G36*
G01X354948Y210837D02*
G02X352240Y210578I-1354J-129D01*
G01X352031Y212769D01*
G02X354739Y213027I1354J129D01*
G01X354948Y210837D01*
G37*
G36*
G01X346240Y210141D02*
X346224Y210306D01*
X346295Y212525D01*
X346321Y212689D01*
G02X349017Y212612I1343J-213D01*
G01X349033Y212447D01*
X348962Y210234D01*
X348954Y210226D01*
X348947Y210154D01*
G02X346240Y210141I-1354J123D01*
G37*
G36*
G01X357162Y209968D02*
X357131Y210131D01*
X357014Y212358D01*
X357026Y212523D01*
G02X359740Y212498I1356J-97D01*
G01X359750Y212299D01*
X359761D01*
X359866Y210293D01*
X359859Y210286D01*
X359858Y210204D01*
G02X357162Y209968I-1360J16D01*
G37*
G36*
G01X337607Y209430D02*
X337566Y211648D01*
G02X340286Y211699I1360J26D01*
G01X340327Y209480D01*
G02X337607Y209430I-1360J-25D01*
G37*
G36*
G01X53370Y187640D02*
G02X50350I-1510J0D01*
G01Y191411D01*
G02X53370Y191410I1510J-1D01*
G01Y187640D01*
G37*
G36*
G01X200951Y187570D02*
G02X197931Y187525I-1510J-23D01*
G01X197882Y190925D01*
G02X200902Y190969I1510J22D01*
G01X200951Y187570D01*
G37*
G36*
G01X59379Y185890D02*
G02Y182870I0J-1510D01*
G01X55719D01*
G02X55720Y185890I1J1510D01*
G01X59379D01*
G37*
G36*
G01X241407Y180504D02*
G02X238393Y180697I-1507J97D01*
G01X238612Y184090D01*
G02X241626Y183896I1507J-97D01*
G01X241407Y180504D01*
G37*
G36*
G01X170910Y175350D02*
G02Y172330I0J-1510D01*
G01X167139D01*
G02X167140Y175350I1J1510D01*
G01X170910D01*
G37*
G36*
G01X177194Y171390D02*
G02X177125Y174410I-35J1510D01*
G01X180897Y174495D01*
G02X180965Y171475I34J-1510D01*
G01X177194Y171390D01*
G37*
G36*
G01X195638Y148605D02*
G02X193608Y150841I-1015J1118D01*
G01X196115Y153119D01*
X196116Y153120D01*
G02X198155Y150892I1024J-1110D01*
G01X195638Y148605D01*
G37*
G36*
G01X236385Y139289D02*
G02X233365Y139290I-1510J1D01*
G01Y143060D01*
G02X236385I1510J0D01*
G01Y139289D01*
G37*
G36*
G01X210551Y140538D02*
G02X210542Y137518I-5J-1510D01*
G01X206785Y137530D01*
G02X206795Y140550I5J1510D01*
G01X210551Y140538D01*
G37*
G36*
G01X205380Y135710D02*
G02Y132690I0J-1510D01*
G01X201898D01*
G02X201899Y135710I1J1510D01*
G01X205380D01*
G37*
G36*
G01X152180Y115499D02*
G02X149160Y115500I-1510J1D01*
G01Y118900D01*
G02X152180I1510J0D01*
G01Y115499D01*
G37*
G36*
G01X210769Y113771D02*
G02X207749I-1510J0D01*
G01Y117431D01*
G02X210769Y117430I1510J-1D01*
G01Y113771D01*
G37*
G36*
G01X273710Y108360D02*
G02X270690Y108345I-1510J-7D01*
G01X270675Y111824D01*
G02X273695Y111838I1510J7D01*
G01X273710Y108360D01*
G37*
G36*
G01X197845Y81870D02*
G02Y78850I0J-1510D01*
G01X194074D01*
G02X194075Y81870I1J1510D01*
G01X197845D01*
G37*
G36*
G01X82886Y62489D02*
G02X82885Y59469I-1J-1510D01*
G01X79115D01*
G02Y62489I0J1510D01*
G01X82886D01*
G37*
G36*
G01X290200Y59410D02*
G02Y56390I0J-1510D01*
G01X286799D01*
G02X286800Y59410I1J1510D01*
G01X290200D01*
G37*
G36*
G01X319201Y58910D02*
G02X319200Y55890I-1J-1510D01*
G01X315800D01*
G02Y58910I0J1510D01*
G01X319201D01*
G37*
G36*
G01X308200D02*
G02Y55890I0J-1510D01*
G01X304799D01*
G02X304800Y58910I1J1510D01*
G01X308200D01*
G37*
G36*
G01X135001D02*
G02X135000Y55890I-1J-1510D01*
G01X131600D01*
G02Y58910I0J1510D01*
G01X135001D01*
G37*
G36*
G01X119201D02*
G02X119200Y55890I-1J-1510D01*
G01X115800D01*
G02Y58910I0J1510D01*
G01X119201D01*
G37*
G36*
G01X327400Y56410D02*
G02Y53390I0J-1510D01*
G01X323999D01*
G02X324000Y56410I1J1510D01*
G01X327400D01*
G37*
G36*
G01X208701D02*
G02X208700Y53390I-1J-1510D01*
G01X205300D01*
G02Y56410I0J1510D01*
G01X208701D01*
G37*
G36*
G01X166464Y55910D02*
G02X166463Y52890I-1J-1510D01*
G01X163063D01*
G02Y55910I0J1510D01*
G01X166464D01*
G37*
G36*
G01X150716D02*
G02X150715Y52890I-1J-1510D01*
G01X147315D01*
G02Y55910I0J1510D01*
G01X150716D01*
G37*
G36*
G01X103451D02*
G02X103450Y52890I-1J-1510D01*
G01X100050D01*
G02Y55910I0J1510D01*
G01X103451D01*
G37*
G36*
G01X88700D02*
G02Y52890I0J-1510D01*
G01X85299D01*
G02X85300Y55910I1J1510D01*
G01X88700D01*
G37*
G36*
G01X174061Y51110D02*
G02X174060Y48090I-1J-1510D01*
G01X170290D01*
G02Y51110I0J1510D01*
G01X174061D01*
G37*
G36*
G01X159060Y50120D02*
G02Y47100I0J-1510D01*
G01X155289D01*
G02X155290Y50120I1J1510D01*
G01X159060D01*
G37*
G36*
G01X236211Y44567D02*
G02Y41547I0J-1510D01*
G01X232590D01*
G02X232591Y44567I1J1510D01*
G01X236211D01*
G37*
G36*
G01X331931Y42505D02*
G02Y39485I0J-1510D01*
G01X328302D01*
G02X328303Y42505I1J1510D01*
G01X331931D01*
G37*
G36*
G01X316254Y42200D02*
G02Y39180I0J-1510D01*
G01X312483D01*
G02X312484Y42200I1J1510D01*
G01X316254D01*
G37*
G36*
G01X300506Y42000D02*
G02Y38980I0J-1510D01*
G01X296735D01*
G02X296736Y42000I1J1510D01*
G01X300506D01*
G37*
G36*
G01X284758D02*
G02Y38980I0J-1510D01*
G01X280987D01*
G02X280988Y42000I1J1510D01*
G01X284758D01*
G37*
G36*
G01X268911D02*
G02X268910Y38980I-1J-1510D01*
G01X265140D01*
G02Y42000I0J1510D01*
G01X268911D01*
G37*
G36*
G01X198073Y41905D02*
G02Y38885I0J-1510D01*
G01X194444D01*
G02X194445Y41905I1J1510D01*
G01X198073D01*
G37*
G36*
G01X245386Y41867D02*
G02X245385Y38847I-1J-1510D01*
G01X241765D01*
G02Y41867I0J1510D01*
G01X245386D01*
G37*
G36*
G01X190267D02*
G02Y38847I0J-1510D01*
G01X186646D01*
G02X186647Y41867I1J1510D01*
G01X190267D01*
G37*
G36*
G01X174519D02*
G02Y38847I0J-1510D01*
G01X170898D01*
G02X170899Y41867I1J1510D01*
G01X174519D01*
G37*
G36*
G01X158771D02*
G02Y38847I0J-1510D01*
G01X155150D01*
G02X155151Y41867I1J1510D01*
G01X158771D01*
G37*
G36*
G01X143024D02*
G02X143023Y38847I-1J-1510D01*
G01X139403D01*
G02Y41867I0J1510D01*
G01X143024D01*
G37*
G36*
G01X127276D02*
G02X127275Y38847I-1J-1510D01*
G01X123655D01*
G02Y41867I0J1510D01*
G01X127276D01*
G37*
G36*
G01X111528D02*
G02X111527Y38847I-1J-1510D01*
G01X107907D01*
G02Y41867I0J1510D01*
G01X111528D01*
G37*
G36*
G01X95779D02*
G02Y38847I0J-1510D01*
G01X92158D01*
G02X92159Y41867I1J1510D01*
G01X95779D01*
G37*
G36*
G01X80031D02*
G02Y38847I0J-1510D01*
G01X76410D01*
G02X76411Y41867I1J1510D01*
G01X80031D01*
G37*
G36*
G01X314988Y52200D02*
G02X315200Y52412I212J0D01*
G01X316800D01*
G02X317012Y52200I0J-212D01*
G01Y50800D01*
G02X316800Y50588I-212J0D01*
G01X315200D01*
G02X314988Y50800I0J212D01*
G01Y52200D01*
G37*
G36*
G01X317988D02*
G02X318200Y52412I212J0D01*
G01X319800D01*
G02X320012Y52200I0J-212D01*
G01Y50800D01*
G02X319800Y50588I-212J0D01*
G01X318200D01*
G02X317988Y50800I0J212D01*
G01Y52200D01*
G37*
G36*
G01X314988Y55200D02*
G02X315200Y55412I212J0D01*
G01X316800D01*
G02X317012Y55200I0J-212D01*
G01Y53800D01*
G02X316800Y53588I-212J0D01*
G01X315200D01*
G02X314988Y53800I0J212D01*
G01Y55200D01*
G37*
G36*
G01X317988D02*
G02X318200Y55412I212J0D01*
G01X319800D01*
G02X320012Y55200I0J-212D01*
G01Y53800D01*
G02X319800Y53588I-212J0D01*
G01X318200D01*
G02X317988Y53800I0J212D01*
G01Y55200D01*
G37*
G36*
G01X306988Y52200D02*
G02X307200Y52412I212J0D01*
G01X308800D01*
G02X309012Y52200I0J-212D01*
G01Y50800D01*
G02X308800Y50588I-212J0D01*
G01X307200D01*
G02X306988Y50800I0J212D01*
G01Y52200D01*
G37*
G36*
G01X303988D02*
G02X304200Y52412I212J0D01*
G01X305800D01*
G02X306012Y52200I0J-212D01*
G01Y50800D01*
G02X305800Y50588I-212J0D01*
G01X304200D01*
G02X303988Y50800I0J212D01*
G01Y52200D01*
G37*
G36*
G01Y55200D02*
G02X304200Y55412I212J0D01*
G01X305800D01*
G02X306012Y55200I0J-212D01*
G01Y53800D01*
G02X305800Y53588I-212J0D01*
G01X304200D01*
G02X303988Y53800I0J212D01*
G01Y55200D01*
G37*
G36*
G01X306988D02*
G02X307200Y55412I212J0D01*
G01X308800D01*
G02X309012Y55200I0J-212D01*
G01Y53800D01*
G02X308800Y53588I-212J0D01*
G01X307200D01*
G02X306988Y53800I0J212D01*
G01Y55200D01*
G37*
G36*
G01X285988Y52700D02*
G02X286200Y52912I212J0D01*
G01X287800D01*
G02X288012Y52700I0J-212D01*
G01Y51300D01*
G02X287800Y51088I-212J0D01*
G01X286200D01*
G02X285988Y51300I0J212D01*
G01Y52700D01*
G37*
G36*
G01Y55700D02*
G02X286200Y55912I212J0D01*
G01X287800D01*
G02X288012Y55700I0J-212D01*
G01Y54300D01*
G02X287800Y54088I-212J0D01*
G01X286200D01*
G02X285988Y54300I0J212D01*
G01Y55700D01*
G37*
G36*
G01X288988Y52700D02*
G02X289200Y52912I212J0D01*
G01X290800D01*
G02X291012Y52700I0J-212D01*
G01Y51300D01*
G02X290800Y51088I-212J0D01*
G01X289200D01*
G02X288988Y51300I0J212D01*
G01Y52700D01*
G37*
G36*
G01Y55700D02*
G02X289200Y55912I212J0D01*
G01X290800D01*
G02X291012Y55700I0J-212D01*
G01Y54300D01*
G02X290800Y54088I-212J0D01*
G01X289200D01*
G02X288988Y54300I0J212D01*
G01Y55700D01*
G37*
G36*
G01X266700Y121212D02*
G02X266912Y121000I0J-212D01*
G01Y119400D01*
G02X266700Y119188I-212J0D01*
G01X265300D01*
G02X265088Y119400I0J212D01*
G01Y121000D01*
G02X265300Y121212I212J0D01*
G01X266700D01*
G37*
G36*
G01Y118212D02*
G02X266912Y118000I0J-212D01*
G01Y116400D01*
G02X266700Y116188I-212J0D01*
G01X265300D01*
G02X265088Y116400I0J212D01*
G01Y118000D01*
G02X265300Y118212I212J0D01*
G01X266700D01*
G37*
G36*
G01Y109512D02*
G02X266912Y109300I0J-212D01*
G01Y107700D01*
G02X266700Y107488I-212J0D01*
G01X265300D01*
G02X265088Y107700I0J212D01*
G01Y109300D01*
G02X265300Y109512I212J0D01*
G01X266700D01*
G37*
G36*
G01Y112512D02*
G02X266912Y112300I0J-212D01*
G01Y110700D01*
G02X266700Y110488I-212J0D01*
G01X265300D01*
G02X265088Y110700I0J212D01*
G01Y112300D01*
G02X265300Y112512I212J0D01*
G01X266700D01*
G37*
G36*
G01X269988Y52700D02*
G02X270200Y52912I212J0D01*
G01X271800D01*
G02X272012Y52700I0J-212D01*
G01Y51300D01*
G02X271800Y51088I-212J0D01*
G01X270200D01*
G02X269988Y51300I0J212D01*
G01Y52700D01*
G37*
G36*
G01X266988D02*
G02X267200Y52912I212J0D01*
G01X268800D01*
G02X269012Y52700I0J-212D01*
G01Y51300D01*
G02X268800Y51088I-212J0D01*
G01X267200D01*
G02X266988Y51300I0J212D01*
G01Y52700D01*
G37*
G36*
G01X263700Y121212D02*
G02X263912Y121000I0J-212D01*
G01Y119400D01*
G02X263700Y119188I-212J0D01*
G01X262300D01*
G02X262088Y119400I0J212D01*
G01Y121000D01*
G02X262300Y121212I212J0D01*
G01X263700D01*
G37*
G36*
G01Y118212D02*
G02X263912Y118000I0J-212D01*
G01Y116400D01*
G02X263700Y116188I-212J0D01*
G01X262300D01*
G02X262088Y116400I0J212D01*
G01Y118000D01*
G02X262300Y118212I212J0D01*
G01X263700D01*
G37*
G36*
G01Y109512D02*
G02X263912Y109300I0J-212D01*
G01Y107700D01*
G02X263700Y107488I-212J0D01*
G01X262300D01*
G02X262088Y107700I0J212D01*
G01Y109300D01*
G02X262300Y109512I212J0D01*
G01X263700D01*
G37*
G36*
G01Y112512D02*
G02X263912Y112300I0J-212D01*
G01Y110700D01*
G02X263700Y110488I-212J0D01*
G01X262300D01*
G02X262088Y110700I0J212D01*
G01Y112300D01*
G02X262300Y112512I212J0D01*
G01X263700D01*
G37*
G36*
G01X263012Y51300D02*
G02X262800Y51088I-212J0D01*
G01X261200D01*
G02X260988Y51300I0J212D01*
G01Y52700D01*
G02X261200Y52912I212J0D01*
G01X262800D01*
G02X263012Y52700I0J-212D01*
G01Y51300D01*
G37*
G36*
G01X260012D02*
G02X259800Y51088I-212J0D01*
G01X258200D01*
G02X257988Y51300I0J212D01*
G01Y52700D01*
G02X258200Y52912I212J0D01*
G01X259800D01*
G02X260012Y52700I0J-212D01*
G01Y51300D01*
G37*
G36*
G01X180988Y49200D02*
G02X181200Y49412I212J0D01*
G01X182800D01*
G02X183012Y49200I0J-212D01*
G01Y47800D01*
G02X182800Y47588I-212J0D01*
G01X181200D01*
G02X180988Y47800I0J212D01*
G01Y49200D01*
G37*
G36*
G01X177988D02*
G02X178200Y49412I212J0D01*
G01X179800D01*
G02X180012Y49200I0J-212D01*
G01Y47800D01*
G02X179800Y47588I-212J0D01*
G01X178200D01*
G02X177988Y47800I0J212D01*
G01Y49200D01*
G37*
G36*
G01X180988Y52200D02*
G02X181200Y52412I212J0D01*
G01X182800D01*
G02X183012Y52200I0J-212D01*
G01Y50800D01*
G02X182800Y50588I-212J0D01*
G01X181200D01*
G02X180988Y50800I0J212D01*
G01Y52200D01*
G37*
G36*
G01X177988D02*
G02X178200Y52412I212J0D01*
G01X179800D01*
G02X180012Y52200I0J-212D01*
G01Y50800D01*
G02X179800Y50588I-212J0D01*
G01X178200D01*
G02X177988Y50800I0J212D01*
G01Y52200D01*
G37*
G36*
G01X162252Y49200D02*
G02X162463Y49412I211J1D01*
G01X164063D01*
G02X164274Y49200I-1J-212D01*
G01Y47800D01*
G02X164063Y47588I-211J-1D01*
G01X162463D01*
G02X162252Y47800I1J212D01*
G01Y49200D01*
G37*
G36*
G01Y52200D02*
G02X162463Y52412I211J1D01*
G01X164063D01*
G02X164274Y52200I-1J-212D01*
G01Y50800D01*
G02X164063Y50588I-211J-1D01*
G01X162463D01*
G02X162252Y50800I1J212D01*
G01Y52200D01*
G37*
G36*
G01X165252Y49200D02*
G02X165463Y49412I211J1D01*
G01X167063D01*
G02X167274Y49200I-1J-212D01*
G01Y47800D01*
G02X167063Y47588I-211J-1D01*
G01X165463D01*
G02X165252Y47800I1J212D01*
G01Y49200D01*
G37*
G36*
G01Y52200D02*
G02X165463Y52412I211J1D01*
G01X167063D01*
G02X167274Y52200I-1J-212D01*
G01Y50800D01*
G02X167063Y50588I-211J-1D01*
G01X165463D01*
G02X165252Y50800I1J212D01*
G01Y52200D01*
G37*
G36*
G01X146504Y49200D02*
G02X146715Y49412I211J1D01*
G01X148315D01*
G02X148526Y49200I-1J-212D01*
G01Y47800D01*
G02X148315Y47588I-211J-1D01*
G01X146715D01*
G02X146504Y47800I1J212D01*
G01Y49200D01*
G37*
G36*
G01Y52200D02*
G02X146715Y52412I211J1D01*
G01X148315D01*
G02X148526Y52200I-1J-212D01*
G01Y50800D01*
G02X148315Y50588I-211J-1D01*
G01X146715D01*
G02X146504Y50800I1J212D01*
G01Y52200D01*
G37*
G36*
G01X149504Y49200D02*
G02X149715Y49412I211J1D01*
G01X151315D01*
G02X151526Y49200I-1J-212D01*
G01Y47800D01*
G02X151315Y47588I-211J-1D01*
G01X149715D01*
G02X149504Y47800I1J212D01*
G01Y49200D01*
G37*
G36*
G01Y52200D02*
G02X149715Y52412I211J1D01*
G01X151315D01*
G02X151526Y52200I-1J-212D01*
G01Y50800D01*
G02X151315Y50588I-211J-1D01*
G01X149715D01*
G02X149504Y50800I1J212D01*
G01Y52200D01*
G37*
G36*
G01X130788Y49200D02*
G02X131000Y49412I212J0D01*
G01X132600D01*
G02X132812Y49200I0J-212D01*
G01Y47800D01*
G02X132600Y47588I-212J0D01*
G01X131000D01*
G02X130788Y47800I0J212D01*
G01Y49200D01*
G37*
G36*
G01Y52200D02*
G02X131000Y52412I212J0D01*
G01X132600D01*
G02X132812Y52200I0J-212D01*
G01Y50800D01*
G02X132600Y50588I-212J0D01*
G01X131000D01*
G02X130788Y50800I0J212D01*
G01Y52200D01*
G37*
G36*
G01X133788Y49200D02*
G02X134000Y49412I212J0D01*
G01X135600D01*
G02X135812Y49200I0J-212D01*
G01Y47800D01*
G02X135600Y47588I-212J0D01*
G01X134000D01*
G02X133788Y47800I0J212D01*
G01Y49200D01*
G37*
G36*
G01Y52200D02*
G02X134000Y52412I212J0D01*
G01X135600D01*
G02X135812Y52200I0J-212D01*
G01Y50800D01*
G02X135600Y50588I-212J0D01*
G01X134000D01*
G02X133788Y50800I0J212D01*
G01Y52200D01*
G37*
G36*
G01X114988Y49200D02*
G02X115200Y49412I212J0D01*
G01X116800D01*
G02X117012Y49200I0J-212D01*
G01Y47800D01*
G02X116800Y47588I-212J0D01*
G01X115200D01*
G02X114988Y47800I0J212D01*
G01Y49200D01*
G37*
G36*
G01Y52200D02*
G02X115200Y52412I212J0D01*
G01X116800D01*
G02X117012Y52200I0J-212D01*
G01Y50800D01*
G02X116800Y50588I-212J0D01*
G01X115200D01*
G02X114988Y50800I0J212D01*
G01Y52200D01*
G37*
G36*
G01X117988Y49200D02*
G02X118200Y49412I212J0D01*
G01X119800D01*
G02X120012Y49200I0J-212D01*
G01Y47800D01*
G02X119800Y47588I-212J0D01*
G01X118200D01*
G02X117988Y47800I0J212D01*
G01Y49200D01*
G37*
G36*
G01Y52200D02*
G02X118200Y52412I212J0D01*
G01X119800D01*
G02X120012Y52200I0J-212D01*
G01Y50800D01*
G02X119800Y50588I-212J0D01*
G01X118200D01*
G02X117988Y50800I0J212D01*
G01Y52200D01*
G37*
G36*
G01X99238Y49200D02*
G02X99450Y49412I212J0D01*
G01X101050D01*
G02X101262Y49200I0J-212D01*
G01Y47800D01*
G02X101050Y47588I-212J0D01*
G01X99450D01*
G02X99238Y47800I0J212D01*
G01Y49200D01*
G37*
G36*
G01Y52200D02*
G02X99450Y52412I212J0D01*
G01X101050D01*
G02X101262Y52200I0J-212D01*
G01Y50800D01*
G02X101050Y50588I-212J0D01*
G01X99450D01*
G02X99238Y50800I0J212D01*
G01Y52200D01*
G37*
G36*
G01X102238Y49200D02*
G02X102450Y49412I212J0D01*
G01X104050D01*
G02X104262Y49200I0J-212D01*
G01Y47800D01*
G02X104050Y47588I-212J0D01*
G01X102450D01*
G02X102238Y47800I0J212D01*
G01Y49200D01*
G37*
G36*
G01Y52200D02*
G02X102450Y52412I212J0D01*
G01X104050D01*
G02X104262Y52200I0J-212D01*
G01Y50800D01*
G02X104050Y50588I-212J0D01*
G01X102450D01*
G02X102238Y50800I0J212D01*
G01Y52200D01*
G37*
G36*
G01X84488Y49200D02*
G02X84700Y49412I212J0D01*
G01X86300D01*
G02X86512Y49200I0J-212D01*
G01Y47800D01*
G02X86300Y47588I-212J0D01*
G01X84700D01*
G02X84488Y47800I0J212D01*
G01Y49200D01*
G37*
G36*
G01Y52200D02*
G02X84700Y52412I212J0D01*
G01X86300D01*
G02X86512Y52200I0J-212D01*
G01Y50800D01*
G02X86300Y50588I-212J0D01*
G01X84700D01*
G02X84488Y50800I0J212D01*
G01Y52200D01*
G37*
G36*
G01X87488Y49200D02*
G02X87700Y49412I212J0D01*
G01X89300D01*
G02X89512Y49200I0J-212D01*
G01Y47800D01*
G02X89300Y47588I-212J0D01*
G01X87700D01*
G02X87488Y47800I0J212D01*
G01Y49200D01*
G37*
G36*
G01Y52200D02*
G02X87700Y52412I212J0D01*
G01X89300D01*
G02X89512Y52200I0J-212D01*
G01Y50800D01*
G02X89300Y50588I-212J0D01*
G01X87700D01*
G02X87488Y50800I0J212D01*
G01Y52200D01*
G37*
G36*
G01X81488Y49200D02*
G02X81700Y49412I212J0D01*
G01X83300D01*
G02X83512Y49200I0J-212D01*
G01Y47800D01*
G02X83300Y47588I-212J0D01*
G01X81700D01*
G02X81488Y47800I0J212D01*
G01Y49200D01*
G37*
G36*
G01Y52200D02*
G02X81700Y52412I212J0D01*
G01X83300D01*
G02X83512Y52200I0J-212D01*
G01Y50800D01*
G02X83300Y50588I-212J0D01*
G01X81700D01*
G02X81488Y50800I0J212D01*
G01Y52200D01*
G37*
G36*
G01X78488Y49200D02*
G02X78700Y49412I212J0D01*
G01X80300D01*
G02X80512Y49200I0J-212D01*
G01Y47800D01*
G02X80300Y47588I-212J0D01*
G01X78700D01*
G02X78488Y47800I0J212D01*
G01Y49200D01*
G37*
G36*
G01Y52200D02*
G02X78700Y52412I212J0D01*
G01X80300D01*
G02X80512Y52200I0J-212D01*
G01Y50800D01*
G02X80300Y50588I-212J0D01*
G01X78700D01*
G02X78488Y50800I0J212D01*
G01Y52200D01*
G37*
G36*
G01X18898Y261012D02*
Y264182D01*
X18899Y264184D01*
X25000D01*
Y261012D01*
X18898D01*
G37*
G36*
G01Y249202D02*
Y252371D01*
X18899Y252372D01*
X25000D01*
Y249202D01*
X18898D01*
G37*
G36*
G01Y255106D02*
Y258277D01*
X18899Y258278D01*
X25000D01*
Y255106D01*
X18898D01*
G37*
G36*
G01Y231484D02*
Y234655D01*
X18899Y234656D01*
X25000D01*
Y231484D01*
X18898D01*
G37*
G36*
G01Y237390D02*
Y240560D01*
X18899Y240562D01*
X25000D01*
Y237390D01*
X18898D01*
G37*
G36*
G01Y243296D02*
Y246466D01*
X18899Y246468D01*
X25000D01*
Y243296D01*
X18898D01*
G37*
G36*
G01Y213768D02*
Y216938D01*
X18899Y216940D01*
X25000D01*
Y213768D01*
X18898D01*
G37*
G36*
G01Y219674D02*
Y222844D01*
X18899Y222846D01*
X25000D01*
Y219674D01*
X18898D01*
G37*
G36*
G01Y225580D02*
Y228749D01*
X18899Y228750D01*
X25000D01*
Y225580D01*
X18898D01*
G37*
G36*
G01X319026Y236350D02*
X316069D01*
G02Y239050I-69J1350D01*
G01X319031D01*
G02Y236350I69J-1350D01*
G01X319026D01*
G37*
G36*
G01X329939Y236762D02*
X329942Y236759D01*
X332041Y234668D01*
X332045Y234664D01*
G02X330148Y232742I-903J-1006D01*
G01X330145Y232745D01*
X328036Y234845D01*
X328033Y234848D01*
G02X329939Y236762I911J999D01*
G37*
G36*
G01X318550Y215226D02*
Y213169D01*
G02X315850I-1350J-69D01*
G01Y215231D01*
G02X318550I1350J69D01*
G01Y215226D01*
G37*
G36*
G01X322950Y210926D02*
Y208769D01*
G02X320250I-1350J-69D01*
G01Y210931D01*
G02X322950I1350J69D01*
G01Y210926D01*
G37*
G36*
G01X36300Y212122D02*
Y208373D01*
G02X33300I-1500J-73D01*
G01Y212127D01*
G02X36300I1500J73D01*
G01Y212122D01*
G37*
G36*
G01X33500Y203122D02*
Y199373D01*
G02X30500I-1500J-73D01*
G01Y203127D01*
G02X33500I1500J73D01*
G01Y203122D01*
G37*
G36*
G01X307505Y124052D02*
X307509D01*
X309573Y124142D01*
X309578D01*
G02X309696Y121444I122J-1346D01*
G01X309691D01*
X307626Y121354D01*
X307621Y121353D01*
G02X307505Y124052I-121J1347D01*
G37*
G36*
G01X309107Y116351D02*
X307051Y116374D01*
X307046D01*
G02X307077Y119074I-52J1351D01*
G01X307081D01*
X309137Y119051D01*
X309142D01*
G02X309111Y116351I52J-1351D01*
G01X309107D01*
G37*
G36*
G01X253422Y56400D02*
X250573D01*
G02Y59400I-73J1500D01*
G01X253427D01*
G02Y56400I73J-1500D01*
G01X253422D01*
G37*
G36*
G01X197622Y52900D02*
X194773D01*
G02Y55900I-73J1500D01*
G01X197627D01*
G02Y52900I73J-1500D01*
G01X197622D01*
G37*
G36*
G01X181722D02*
X179073D01*
G02Y55900I-73J1500D01*
G01X181727D01*
G02Y52900I73J-1500D01*
G01X181722D01*
G37*
G36*
G01X189622Y52800D02*
X186938D01*
G02Y55800I-73J1500D01*
G01X189627D01*
G02Y52800I73J-1500D01*
G01X189622D01*
G37*
G36*
G01X268800Y54088D02*
X267200D01*
G02X266988Y54300I0J212D01*
G01Y55700D01*
G02X267035Y55832I212J-1D01*
G03X266989Y56378I-313J249D01*
G02X268000Y59010I1011J1122D01*
G01X271000D01*
G02X272011Y56378I0J-1510D01*
G03X271965Y55832I267J-297D01*
G02X272012Y55700I-165J-133D01*
G01Y54300D01*
G02X271800Y54088I-212J0D01*
G01X270200D01*
G02X269988Y54300I0J212D01*
G01Y55700D01*
G02X269994Y55746I211J-4D01*
G01X269998Y55768D01*
Y55990D01*
X269002D01*
Y55768D01*
X269006Y55746D01*
G02X269012Y55700I-205J-50D01*
G01Y54300D01*
G02X268800Y54088I-212J0D01*
G37*
G36*
G01X259800D02*
X258200D01*
G02X257988Y54300I0J212D01*
G01Y55700D01*
G02X258200Y55912I212J0D01*
G01X258986D01*
Y56288D01*
X258811Y56310D01*
G02X259073Y59300I190J1490D01*
G01X261927D01*
G02X262189Y56310I72J-1500D01*
G01X262014Y56288D01*
Y55912D01*
X262800D01*
G02X263012Y55700I0J-212D01*
G01Y54300D01*
G02X262800Y54088I-212J0D01*
G01X261200D01*
G02X260988Y54300I0J212D01*
G01Y55700D01*
G02X261000Y55769I212J-1D01*
G03X260622Y56300I-378J131D01*
G01X260378D01*
G03X260000Y55769I0J-400D01*
G02X260012Y55700I-200J-70D01*
G01Y54300D01*
G02X259800Y54088I-212J0D01*
G37*
G54D40*
X37600Y198800D03*
Y203700D03*
X40400Y207800D03*
Y212700D03*
G54D37*
X144000Y67875D03*
Y147125D03*
G54D36*
X42717Y270472D03*
X235630Y75590D03*
X492520Y262598D03*
X761417Y22798D03*
G54D38*
X235630Y174016D03*
X498425Y22798D03*
X755512Y262598D03*
G54D35*
X42717Y191732D03*
G54D39*
X804032Y27032D03*
Y67032D03*
G54D32*
X350197Y231103D03*
G54D33*
X11500Y68500D03*
X12000Y279000D03*
X816000Y280000D03*
G54D34*
X45669Y77185D03*
Y172460D03*
G54D15*
X17500Y190200D03*
X16844Y203100D03*
X13090Y231129D03*
Y234899D03*
X7600Y240861D03*
Y237091D03*
X13590Y242940D03*
Y254751D03*
X7600Y252672D03*
Y248902D03*
Y260713D03*
X13590Y258521D03*
Y246710D03*
X16900Y269000D03*
X7600Y264483D03*
X28400Y81400D03*
X30000Y136000D03*
X29700Y141200D03*
X26500Y181800D03*
X33500Y178100D03*
X33150Y181500D03*
X29400Y180000D03*
X23100Y181800D03*
X33500Y196100D03*
X32000Y203200D03*
Y199300D03*
X41200Y90300D03*
X42000Y96000D03*
X41500Y100800D03*
X40500Y124300D03*
X37600Y198800D03*
X37900Y195300D03*
X40400Y212700D03*
X34800Y208300D03*
X40400Y207800D03*
X34800Y212200D03*
X37600Y203700D03*
X44861Y227261D03*
X37900Y219000D03*
Y222500D03*
Y229500D03*
Y226000D03*
Y240000D03*
Y243500D03*
Y233000D03*
X38000Y236500D03*
X44400Y250400D03*
X37900Y257500D03*
Y254000D03*
Y247000D03*
X38000Y250500D03*
X46800Y274500D03*
X62900Y79900D03*
X60800Y87500D03*
X53500Y120400D03*
X57600Y136900D03*
X56100Y130700D03*
X52643Y130800D03*
X58000Y141750D03*
X58800Y177000D03*
X51860Y187640D03*
Y191410D03*
X59379Y184380D03*
X55720D03*
X57400Y210700D03*
X57009Y230009D03*
X57600Y226600D03*
X57500Y223200D03*
X57287Y219806D03*
X56724Y243300D03*
X56800Y249613D03*
X58102Y246471D03*
X57800Y253900D03*
X50000Y270000D03*
X57800Y264100D03*
X64700Y272500D03*
X57800Y267500D03*
X80031Y40357D03*
X76411D03*
X79700Y67500D03*
X79115Y60979D03*
X69235Y99735D03*
X68200Y94900D03*
Y91500D03*
X66500Y128000D03*
X65500Y123800D03*
X74800Y191000D03*
X72600Y244800D03*
X75600Y246700D03*
X79000Y246900D03*
X69400Y246000D03*
X75300Y259900D03*
X78200Y275600D03*
X71800Y268800D03*
X66800Y275200D03*
X74000Y271400D03*
X92159Y40357D03*
X88700Y54400D03*
X85300D03*
X90600Y63200D03*
X94000Y63300D03*
X82885Y60979D03*
X90000Y91000D03*
X91500Y84000D03*
X94500Y76200D03*
X89800Y87300D03*
X86100Y97700D03*
X90500Y101000D03*
X86500Y113500D03*
X80500D03*
X85500Y135400D03*
X83500Y191000D03*
X86900D03*
X84700Y197100D03*
X92900Y204008D03*
X89500Y204000D03*
X85898Y200598D03*
X95200Y216200D03*
X90812Y215000D03*
X80563Y214700D03*
X88900Y246700D03*
X82400Y246600D03*
X82100Y259600D03*
X80500Y269500D03*
X83900D03*
X95779Y40357D03*
X107907D03*
X109700Y60000D03*
X103450Y54400D03*
X100050D03*
X109600Y63700D03*
X96200Y60700D03*
X97900Y76200D03*
X106100Y158700D03*
X97100Y189200D03*
X110000Y201900D03*
X107740Y204460D03*
X102000Y203200D03*
X100600Y221100D03*
X110166Y239500D03*
X109500Y258300D03*
X97600Y246500D03*
X104900Y248800D03*
X120000Y40700D03*
X123655Y40357D03*
X111527D03*
X120200Y45610D03*
X119200Y57400D03*
X115800D03*
X111200Y67200D03*
X121170Y80900D03*
X121295Y77502D03*
X126000Y86200D03*
X125787Y78813D03*
X120700Y135500D03*
X118500Y125500D03*
X112550Y142800D03*
X119600Y143300D03*
X111900Y209000D03*
X112800Y225400D03*
X112700Y221200D03*
Y231400D03*
X136600Y44800D03*
X139403Y40357D03*
X127275D03*
X138000Y49800D03*
X138574Y57924D03*
X131600Y57400D03*
X135000D03*
X136469Y89902D03*
X130315Y90533D03*
X134200Y86100D03*
X137138Y76512D03*
X129300Y84900D03*
X136600Y93300D03*
X133558Y91779D03*
X136500Y104923D03*
X130000Y121000D03*
X136540Y108620D03*
X133975Y129141D03*
X130563Y125200D03*
X127500Y129180D03*
X126950Y125200D03*
X133786Y134700D03*
X130300Y135000D03*
X135412Y141400D03*
X138600Y146300D03*
X131500Y149000D03*
X136156Y138025D03*
X131762Y141796D03*
X127200Y158700D03*
X137300Y158900D03*
X140800D03*
X140000Y195500D03*
X137100Y188900D03*
X128000Y203300D03*
X143023Y40357D03*
X155151D03*
X144995Y57995D03*
X155290Y48610D03*
X143688Y48350D03*
X147400Y60400D03*
X147315Y54400D03*
X150715D03*
X153000Y67800D03*
X150894Y76497D03*
X154294Y76506D03*
X150670Y102720D03*
X154550Y106200D03*
X151080Y99344D03*
X154550Y102800D03*
X150670Y115500D03*
Y118900D03*
X157229Y119218D03*
X153693Y124807D03*
X147808Y145208D03*
X142900Y138595D03*
X146400D03*
X150804Y158896D03*
X144500Y158900D03*
X146980Y200580D03*
X153000Y201900D03*
X153500Y210000D03*
X146396Y207675D03*
X142997Y207891D03*
X150000Y210100D03*
X146500Y236500D03*
X146000Y231000D03*
X155300Y254000D03*
X144200Y270700D03*
X158771Y40357D03*
X170899D03*
X159060Y48610D03*
X170290Y49600D03*
X166463Y54400D03*
X163063D03*
X164000Y65000D03*
X172199Y91591D03*
X172300Y107189D03*
X158305Y112180D03*
X157500Y149025D03*
X158500Y161820D03*
X161900Y161700D03*
X167581Y164084D03*
X170910Y173840D03*
X167140D03*
X165900Y181500D03*
X163700Y178900D03*
X165700Y254000D03*
X174519Y40357D03*
X186647D03*
X174060Y49600D03*
X186865Y54300D03*
X181800Y54400D03*
X179000D03*
X179800Y65700D03*
X176900Y67500D03*
X180700Y78500D03*
X174900Y77700D03*
X183726Y106353D03*
X187500Y106500D03*
X173000Y97000D03*
X183344Y94056D03*
X179400Y94200D03*
X181732Y97500D03*
X178000Y97300D03*
X175787Y127000D03*
X176700Y144875D03*
X177200Y148700D03*
X181000Y167500D03*
X180931Y172985D03*
X177159Y172900D03*
X186300Y172400D03*
X174739Y207381D03*
X187000Y209500D03*
X198073Y40395D03*
X194445D03*
X190267Y40357D03*
X189700Y54300D03*
X197700Y54400D03*
X194700D03*
X190100Y68700D03*
X193500D03*
X194075Y80360D03*
X197845D03*
X202200Y89500D03*
X191500Y94100D03*
X188900Y91800D03*
X193005Y97155D03*
X195989Y95300D03*
X189106Y97235D03*
X201650Y111200D03*
X201899Y134200D03*
X194900Y124200D03*
X197140Y152010D03*
X194623Y149723D03*
X191200Y181068D03*
X199441Y187547D03*
X199392Y190947D03*
X202761Y186811D03*
X195630Y192770D03*
X198198Y206374D03*
X194800Y206100D03*
X201596Y206504D03*
X195000Y234000D03*
X205300Y54900D03*
X208700D03*
X214942Y67242D03*
X211600Y82100D03*
X212300Y85500D03*
X207200Y106000D03*
X209259Y113771D03*
Y117430D03*
X206605Y121741D03*
X209900Y120900D03*
X205380Y134200D03*
X210547Y139028D03*
X206790Y139040D03*
X215100Y194200D03*
X207861Y188540D03*
X215100Y199400D03*
X205000Y206500D03*
X215384Y202984D03*
X216000Y219500D03*
X208800D03*
X212500D03*
X206000Y234000D03*
X229300Y42950D03*
X232591Y43057D03*
X219900Y39100D03*
X223475Y53300D03*
X219899Y56800D03*
X233981Y59125D03*
X221400Y64500D03*
X230400Y63000D03*
X223800Y61700D03*
X230000Y66400D03*
X226500Y94450D03*
X227850Y97575D03*
X230875Y106300D03*
X227894Y104600D03*
X232600Y95300D03*
X227800Y101200D03*
X233452Y108588D03*
X228000Y108304D03*
Y139700D03*
X232921Y167505D03*
X227870Y170252D03*
X224200Y180200D03*
X232560Y204250D03*
X227000Y275500D03*
X236211Y43057D03*
X245385Y40357D03*
X241765D03*
X244400Y50600D03*
X235400Y63400D03*
X240297D03*
X243200Y73700D03*
X240300Y67200D03*
X246600Y73700D03*
X244759Y85200D03*
X236700Y88500D03*
X241200Y94900D03*
X244800Y100700D03*
X235075Y105600D03*
X234875Y139290D03*
Y143060D03*
X244715Y159785D03*
X239900Y180600D03*
X247596Y174667D03*
X240119Y183993D03*
X240100Y191000D03*
X246689Y196687D03*
X254600Y41100D03*
X265140Y40490D03*
X259000Y57800D03*
X250500Y57900D03*
X262000Y57800D03*
X253500Y57900D03*
X264500Y73100D03*
X253700Y75875D03*
X250300Y73800D03*
X264125Y79350D03*
X259820Y103454D03*
X262131Y100959D03*
X258634Y95850D03*
X263775Y140327D03*
X257977Y163423D03*
X264600Y173100D03*
X257687Y169870D03*
X253500Y174360D03*
X261300Y188300D03*
X253300Y189834D03*
X262700Y191500D03*
X261200Y209700D03*
X263600Y239850D03*
Y252700D03*
X257500Y266645D03*
X260500Y264630D03*
X269800Y44800D03*
X275300Y44900D03*
X278700Y44800D03*
X268910Y40490D03*
X278868Y56000D03*
X271000Y57500D03*
X268000D03*
X275200Y78700D03*
X275900Y88200D03*
X280100Y89100D03*
X272200Y108352D03*
X272185Y111831D03*
X278075Y116475D03*
X272300Y129442D03*
X268900Y129386D03*
X280400Y129225D03*
X272300Y149900D03*
X267187Y149800D03*
X278000Y141900D03*
X273900Y156198D03*
X270500Y163200D03*
X274100Y163300D03*
X267456Y160156D03*
X267100Y156200D03*
X272380Y159240D03*
X270500Y156250D03*
X268283Y173035D03*
X278300Y173300D03*
X276910Y189400D03*
X273060Y189374D03*
X266140Y191850D03*
X270341Y211835D03*
X278450Y216800D03*
X265259Y216659D03*
X270774Y222226D03*
X275400Y237900D03*
X267275Y253400D03*
X265500Y249300D03*
X269800Y250700D03*
X278700Y254240D03*
X275300Y254100D03*
X267000Y271300D03*
X284758Y40490D03*
X280988D03*
X286800Y57900D03*
X290200D03*
X288400Y94200D03*
X288100Y99500D03*
X281005Y99105D03*
X281475Y116475D03*
X286500Y119900D03*
X286600Y136000D03*
X287071Y173154D03*
X282950Y181350D03*
X282460Y189400D03*
X286300Y191885D03*
X293300Y212400D03*
X291201Y225025D03*
X287802Y225200D03*
X287600Y238100D03*
X287400Y254100D03*
X295500Y253500D03*
X285000Y261700D03*
X281599Y261799D03*
X287250Y269250D03*
X296736Y40490D03*
X300506D03*
X300900Y46900D03*
X308200Y57400D03*
X304800D03*
X297150Y91100D03*
X309400Y82100D03*
X299800Y85950D03*
Y82300D03*
X304400Y88400D03*
X301300Y97000D03*
X301600Y93300D03*
X303400Y98500D03*
X303376Y95200D03*
X299300Y98500D03*
X296564Y136311D03*
Y127500D03*
X296531Y133061D03*
X301109Y146156D03*
X300700Y142850D03*
X297000Y160200D03*
X307231Y164059D03*
X310579Y182800D03*
X306612Y171882D03*
X304400Y182000D03*
X302591Y173906D03*
X309112Y171960D03*
X309200Y180500D03*
X305091Y173888D03*
X301745Y181788D03*
X307200Y182000D03*
X296600Y189100D03*
X305300Y203125D03*
X307300Y224900D03*
X304400D03*
X309900D03*
X298900Y253300D03*
X309400Y253600D03*
X306000D03*
X302600D03*
X304300Y262900D03*
X309000Y266700D03*
X311300Y277800D03*
X321900Y44000D03*
X312484Y40690D03*
X316254D03*
X314800Y48625D03*
X311950Y50800D03*
X320400Y48600D03*
X324000Y54900D03*
X324176Y48600D03*
X315800Y57400D03*
X319200D03*
X312400Y79700D03*
X312150Y100682D03*
X326000Y254100D03*
X315500D03*
X322500Y254200D03*
X319000D03*
X311400Y269200D03*
X326100Y267000D03*
X322000Y264300D03*
X318600D03*
X313824Y280255D03*
X316945Y281606D03*
X316400Y276800D03*
X319400Y278800D03*
X322700Y277700D03*
X321600Y282500D03*
X325100Y281500D03*
X331931Y40995D03*
X328303D03*
X331300Y48475D03*
X327577D03*
X327400Y54900D03*
X333600Y63800D03*
X356432Y43657D03*
X356971Y37700D03*
X349900Y263800D03*
X342600Y277900D03*
X364600Y44298D03*
X367497Y41042D03*
X363604D03*
X371457Y37642D03*
X367520D03*
X366484Y47129D03*
X362626Y47068D03*
X366700Y68700D03*
X369500Y237200D03*
Y240600D03*
X373000Y242300D03*
X369500Y234600D03*
X373000Y236000D03*
Y238900D03*
X369500Y244000D03*
X365800Y264900D03*
X362400D03*
X369300D03*
X385300Y47000D03*
X388000Y72963D03*
X382700Y275300D03*
X380000Y263461D03*
X383500D03*
X376500D03*
X386100Y275300D03*
X379300D03*
X394229Y241128D03*
X391788Y238760D03*
X399438Y243839D03*
X401838Y246248D03*
X390500Y268800D03*
X393000Y275000D03*
X400900Y273000D03*
X391000Y265000D03*
X417000Y258000D03*
X416128Y272896D03*
X425400Y9103D03*
X422000D03*
X428800D03*
X432200D03*
X430000Y21500D03*
Y27358D03*
X424543Y22208D03*
Y27900D03*
X426405Y25054D03*
X427000Y17000D03*
X423500Y16885D03*
X423000Y43900D03*
X430000Y30758D03*
X424536Y34800D03*
X430000Y34158D03*
X424599Y31300D03*
X422986Y40350D03*
X430000Y244450D03*
X426600D03*
X420000Y244000D03*
X420500Y257800D03*
X433129Y245783D03*
X423600Y246700D03*
X423000Y274000D03*
X433300Y274100D03*
X426600D03*
X429900Y274940D03*
X442100Y7006D03*
X437061Y10393D03*
X434900Y6925D03*
X446800Y9900D03*
X438300Y6925D03*
X449600Y5900D03*
X446200D03*
X446100Y18700D03*
X441390Y28680D03*
X436240Y26300D03*
X449734Y18681D03*
X441281Y17025D03*
X436100Y30900D03*
X436106Y34506D03*
X435700Y243250D03*
X440600Y274300D03*
X449400Y273700D03*
X436600Y275000D03*
X450200Y9800D03*
X451300Y21700D03*
X464000Y275200D03*
X460400D03*
X452500D03*
X469000D03*
X472400Y275100D03*
X466500Y272800D03*
X472101Y266090D03*
X475500Y265900D03*
X479000D03*
X493000Y119299D03*
X495400Y183500D03*
X482400Y266200D03*
X502000Y89000D03*
X498500Y88995D03*
X508000Y119500D03*
X511500D03*
X511200Y183400D03*
X500900D03*
X504400D03*
X510675Y209700D03*
X505315Y268500D03*
X497002Y275400D03*
X525740Y88960D03*
X522280Y89810D03*
X515502Y88998D03*
X518902Y88987D03*
X518200Y183400D03*
X526600Y183500D03*
X514800Y183400D03*
X513100Y234500D03*
X516500D03*
X528985Y89975D03*
X533267Y89634D03*
X539574Y88990D03*
X533000Y119500D03*
X536400D03*
X528100D03*
X528400Y145041D03*
X541550Y183550D03*
X534750Y183600D03*
X538150D03*
X530214Y183481D03*
X531500Y219500D03*
X541500Y234900D03*
X551800Y69600D03*
X548400Y69700D03*
X555199D03*
X556500Y89000D03*
X546349Y89512D03*
X552900Y89100D03*
X542950Y89400D03*
X555500Y183500D03*
X548354Y183600D03*
X544954D03*
X551754D03*
X548300Y209700D03*
X551700Y209800D03*
X550400Y222285D03*
X561999Y69700D03*
X558599D03*
X570715Y89100D03*
X566000D03*
X572845Y183300D03*
X566897Y183405D03*
X561900Y183600D03*
X564398Y183481D03*
X569395Y183300D03*
X558915Y183603D03*
X558300Y210000D03*
X561000Y222700D03*
X561196Y227366D03*
X569200Y223600D03*
X564200Y224000D03*
X575000Y89100D03*
X587500Y88913D03*
X578400Y89100D03*
X588600Y124700D03*
X584800Y183300D03*
X582254Y183313D03*
X576295Y183400D03*
X588475Y183300D03*
X578795D03*
X573600Y190100D03*
X586800Y213200D03*
X583800Y207200D03*
X580350Y207250D03*
X599500Y87500D03*
X590898Y89045D03*
X596845Y89624D03*
X593400Y126000D03*
X592200Y145000D03*
X595744Y145041D03*
X599150Y180300D03*
X593475Y183275D03*
X601750Y182500D03*
X590975Y183275D03*
X594350Y187725D03*
X591850D03*
X588800Y205900D03*
X591363Y208387D03*
X602800Y203225D03*
X601200Y207700D03*
X603964Y210400D03*
X612120Y121750D03*
X608360Y121800D03*
X608300Y144890D03*
X618500Y159000D03*
X605600Y186650D03*
X609345Y190100D03*
X607500Y188300D03*
X616100Y197400D03*
X634000Y97500D03*
X630700Y100500D03*
X627500Y104900D03*
X620000Y112575D03*
X624726Y107395D03*
X621100Y124900D03*
X625500Y159000D03*
X629000D03*
X622000D03*
X633319Y155008D03*
X631900Y175850D03*
X634748Y177708D03*
X633100Y198300D03*
X626300Y198250D03*
X629700Y198300D03*
X622873Y204200D03*
X642823Y88477D03*
X640677Y91115D03*
X638500Y94000D03*
X635000Y110500D03*
X638000Y107400D03*
X648500Y144000D03*
X636719Y154972D03*
X643500Y155000D03*
X640110Y155272D03*
X640461Y181410D03*
X642600Y186400D03*
X646000D03*
X636500Y198300D03*
X653600Y122400D03*
X656477Y148033D03*
X656642Y151430D03*
X656200Y144000D03*
X650500Y155000D03*
X661000Y173800D03*
X657722Y193800D03*
X661600Y197300D03*
X654851Y191978D03*
X663800Y199900D03*
X673100Y179455D03*
X673044Y190456D03*
X668732Y204555D03*
X666446Y202037D03*
X682600Y114300D03*
X689400Y178900D03*
X689547Y175500D03*
X686700Y187400D03*
X687456Y183944D03*
X705145Y93500D03*
X707209Y97500D03*
X698970Y118149D03*
X699241Y114759D03*
X709500Y143500D03*
X709900Y139900D03*
X701245Y183800D03*
X718900Y94000D03*
X726800Y95500D03*
X724200Y108400D03*
X714000Y118500D03*
X727448Y128893D03*
X714900Y131900D03*
X718200Y147000D03*
Y150400D03*
X718825Y155453D03*
X712700Y155978D03*
X724400Y176025D03*
X725500Y195500D03*
X727400Y227400D03*
X736900Y98500D03*
X730200Y94900D03*
X742100Y118200D03*
X736300Y118000D03*
X729400Y120200D03*
X732000Y122700D03*
X728900Y132976D03*
X727800Y136600D03*
X740300Y164700D03*
X727800Y176600D03*
X733000Y176200D03*
X739900Y212800D03*
X731000Y210200D03*
X739800Y216300D03*
X750100Y16100D03*
X749500Y101500D03*
X751300Y118200D03*
X754000Y115100D03*
X748800Y115800D03*
X757900Y124700D03*
X743100Y195500D03*
X743000Y211000D03*
X744100Y221900D03*
X743800Y215900D03*
X758916Y104250D03*
X762304Y103957D03*
X765500Y112000D03*
X769800Y133000D03*
X759400Y131000D03*
X771300Y140200D03*
X766600Y139800D03*
X762000Y281000D03*
X765400D03*
X774500Y31307D03*
X778000D03*
X787600Y183300D03*
X787800Y179900D03*
X793000Y174500D03*
X805500Y128000D03*
G54D20*
X196800Y62600D03*
X199600Y160100D03*
X502500Y6200D03*
X538300Y15200D03*
X699000Y162255D03*
X756400Y110500D03*
X786500Y13500D03*
X782000Y137000D03*
X790500Y11000D03*
X799000Y121500D03*
Y125500D03*
X800400Y158500D03*
X799900Y168800D03*
X811000Y130000D03*
Y134000D03*
X809000Y149200D03*
X811000Y138000D03*
X811200Y141600D03*
X809500Y156900D03*
X809600Y160500D03*
X809700Y164300D03*
G54D13*
X15400Y118000D03*
X10900D03*
X15500Y122800D03*
X15000Y127500D03*
X11000Y122800D03*
X10500Y127500D03*
X11500Y163700D03*
Y159000D03*
X7000Y163700D03*
Y159000D03*
X33000Y105000D03*
X30200Y145000D03*
Y149200D03*
X34000Y161500D03*
X30300Y157600D03*
X30200Y153400D03*
X37500Y105000D03*
X42000D03*
X37500Y264000D03*
X63500Y43500D03*
Y57500D03*
Y48000D03*
Y52500D03*
X63200Y194900D03*
X68500Y47500D03*
X73500Y48000D03*
X68000Y52500D03*
X70900Y193800D03*
X82000Y177500D03*
X104000Y106600D03*
Y115500D03*
Y111000D03*
X100000Y267400D03*
X100700Y262900D03*
X119400Y106700D03*
X123800Y102500D03*
X123900Y106700D03*
X119400Y102300D03*
Y115900D03*
Y111200D03*
X123900Y115900D03*
Y111200D03*
X113200Y146700D03*
X113100Y151000D03*
X117500Y146950D03*
X119000Y159100D03*
X114700Y158800D03*
X116500Y211200D03*
X134100Y96600D03*
X128500Y165000D03*
X129500Y252500D03*
X129000Y268000D03*
X166500Y241000D03*
X186500Y276500D03*
Y281000D03*
X189000Y87700D03*
X192500Y161900D03*
X192600Y166700D03*
X201200Y164200D03*
X191100Y276600D03*
X190900Y280800D03*
X216261Y74846D03*
X212300Y157300D03*
X212600Y161500D03*
X212400Y281200D03*
X217000Y281000D03*
X212500Y277000D03*
X208000D03*
X226900Y133300D03*
X234525Y239250D03*
X229700Y234700D03*
X225300Y239200D03*
X234525Y243450D03*
X229725D03*
X225300Y243400D03*
X234525Y234800D03*
X225300D03*
X229675Y239000D03*
X233500Y258958D03*
X228000Y259000D03*
X240130Y77300D03*
X236400Y95100D03*
X240565Y113365D03*
X249350Y199400D03*
X247500Y239250D03*
X243300Y235050D03*
X247500Y243450D03*
X243300D03*
X238900D03*
X243300Y239250D03*
X247500Y235050D03*
X238925Y235000D03*
Y239200D03*
X248000Y259000D03*
X238500D03*
X243000D03*
X258400Y65600D03*
X252350Y202350D03*
X251700Y239250D03*
Y243450D03*
X252500Y259000D03*
X253000Y267000D03*
X294800Y94100D03*
X339638Y67138D03*
X334500Y266300D03*
X334300Y270500D03*
X335700Y278751D03*
X331500D03*
X345089Y73089D03*
X353500Y71900D03*
X357000Y69500D03*
X349300Y83000D03*
X345100D03*
X354200Y76400D03*
X343600Y270500D03*
X371400Y42500D03*
X371500Y47000D03*
X359800Y72700D03*
X362700Y69600D03*
X380000Y38100D03*
X375600Y42500D03*
X380300D03*
X375700Y47000D03*
X380295Y46779D03*
X505200Y215000D03*
X496711Y248999D03*
X527000Y225500D03*
X600900Y230200D03*
X615700D03*
X630000Y55300D03*
X623400Y230100D03*
X640500Y55000D03*
X655133Y55833D03*
X659811Y260757D03*
X657500Y258400D03*
X661308Y263698D03*
X655500Y270500D03*
X657787Y264179D03*
X656000Y261400D03*
X655523Y266616D03*
X658667Y267622D03*
X721200Y65100D03*
X732000Y63500D03*
X753500Y24007D03*
Y20007D03*
Y28507D03*
X755500Y16000D03*
X770500Y13007D03*
X767500Y24007D03*
X760500Y29000D03*
X761000Y16007D03*
X767500Y28507D03*
Y19507D03*
X764200Y44200D03*
X767500Y33207D03*
X759000Y37507D03*
X764500Y54000D03*
X764300Y49200D03*
X769500Y50000D03*
X761000Y58500D03*
X787500Y93000D03*
X783000D03*
X785830Y188700D03*
X785400Y202800D03*
X789000Y204979D03*
X789200Y214200D03*
Y209800D03*
X784500Y222500D03*
X789000Y223500D03*
X789200Y218700D03*
X786000Y228000D03*
Y232400D03*
X786200Y236900D03*
X786300Y241500D03*
X785000Y245800D03*
Y250200D03*
Y254900D03*
X792000Y83000D03*
X796500D03*
X792000Y87700D03*
X796500D03*
X799200Y98600D03*
X803100Y106000D03*
X799200Y102800D03*
X799000Y107100D03*
X803500Y116700D03*
Y112500D03*
X799000Y116100D03*
Y111900D03*
X789910Y187679D03*
X794110D03*
X798310Y187779D03*
X793500Y204979D03*
Y223500D03*
X793200Y228400D03*
Y232600D03*
Y237200D03*
Y242400D03*
X793300Y247200D03*
X795300Y260800D03*
X795400Y251700D03*
X795300Y256500D03*
Y265000D03*
X810100Y275000D03*
X812035Y271067D03*
X810100Y267339D03*
X812000Y263500D03*
G54D18*
X42717Y270472D03*
X235630Y75590D03*
X492520Y262598D03*
D03*
X761417Y22798D03*
D03*
X804032Y27032D03*
X794032D03*
X804032Y37032D03*
Y47032D03*
X794032Y37032D03*
Y47032D03*
X804032Y57032D03*
X794032D03*
X804032Y67032D03*
X794032D03*
G54D22*
X235630Y174016D03*
X498425Y22798D03*
D03*
X755512Y262598D03*
D03*
G54D24*
X303610Y110800D03*
X309000Y114700D03*
X306700D03*
X309194Y117700D03*
X306994Y117725D03*
X304149Y128349D03*
X307854Y130539D03*
X309700Y122796D03*
X309500Y132925D03*
X307298Y132697D03*
X307500Y122700D03*
X305050Y151150D03*
X309000Y137600D03*
X306961Y153717D03*
X306696Y158610D03*
X309000Y158806D03*
X309220Y153698D03*
X305800Y195400D03*
X303500D03*
X303480Y189100D03*
X301300Y188700D03*
X309700Y187997D03*
X307500Y188000D03*
X317641Y90956D03*
X325081Y100631D03*
X322075Y100650D03*
X323120Y92400D03*
X319520Y92419D03*
X318900Y98000D03*
X317600Y93625D03*
X326162Y91438D03*
X315950Y98650D03*
X320992Y112180D03*
X319096Y113300D03*
X319418Y123225D03*
X315451Y123219D03*
X323900Y129900D03*
X325418Y127349D03*
X325746Y133702D03*
X323300Y147046D03*
X326322Y138434D03*
X325763Y141958D03*
X325200Y149319D03*
X319704Y162804D03*
X323000Y153900D03*
X324029Y166384D03*
X326234Y153969D03*
X323500Y180063D03*
X323121Y182913D03*
X326408Y182292D03*
X316844Y196010D03*
X319801Y194890D03*
X326550Y191600D03*
X322256Y198618D03*
X323331Y196696D03*
X325642Y202325D03*
X321600Y208700D03*
Y211000D03*
X317200Y213100D03*
Y215300D03*
X316000Y237700D03*
X319100D03*
X329300Y87300D03*
X331200Y88600D03*
X330100Y100200D03*
Y98000D03*
X336750Y93500D03*
Y95704D03*
X328000Y92700D03*
X330900Y93400D03*
X333313Y103693D03*
X329415Y119923D03*
X333601Y120500D03*
X333534Y118040D03*
X333434Y106668D03*
X341200Y112569D03*
X338768Y116755D03*
Y119755D03*
X329308Y122386D03*
X338329Y135665D03*
X329031Y125428D03*
X335303Y135178D03*
X336900Y127600D03*
X333977Y127678D03*
X327854Y130434D03*
X338470Y138177D03*
X335450Y150900D03*
X327963Y142008D03*
X335514Y138220D03*
X338320Y141300D03*
X327390Y149106D03*
X336920Y146130D03*
X329421Y138228D03*
X327696Y146108D03*
X330163Y142008D03*
X332478Y138255D03*
X341342Y138224D03*
X333750Y145950D03*
X339491Y143163D03*
X329800Y150800D03*
X332000D03*
X330300Y158546D03*
X339784Y161847D03*
X335499Y153846D03*
X327800Y161500D03*
X336900Y161600D03*
X336800Y164434D03*
X341390Y153991D03*
X329161Y153830D03*
X335964Y158512D03*
X341400Y156700D03*
X331000Y164500D03*
X330900Y161700D03*
X333000Y158300D03*
X339747Y164478D03*
X339300Y174100D03*
X330821Y177402D03*
X329442Y169463D03*
X327708Y177241D03*
X332353Y169522D03*
X337000Y174102D03*
X327600Y174174D03*
X330027Y174119D03*
X334700Y174100D03*
X336915Y177423D03*
X337863Y180545D03*
X330280Y180900D03*
X332500D03*
X335400Y196300D03*
X337800Y189200D03*
X326850Y193900D03*
X329972Y196400D03*
Y193559D03*
X333996Y192063D03*
X334707Y189383D03*
X337800Y192200D03*
X329313Y188000D03*
X335739Y199317D03*
X336500Y204600D03*
X338926Y211674D03*
X338967Y209455D03*
X331658Y212660D03*
X327216Y203902D03*
X328510Y218320D03*
X327024Y220024D03*
X337307Y217961D03*
X331616Y214860D03*
X337341Y215731D03*
X328945Y235846D03*
X331142Y233658D03*
X346596Y118163D03*
Y115163D03*
X343570Y112561D03*
X346495Y130000D03*
X349149Y124141D03*
X351500Y136000D03*
X343000Y126200D03*
X343146Y128473D03*
X347641Y133479D03*
X342533Y133822D03*
X357300Y128600D03*
X355400Y137100D03*
X354300Y128600D03*
X346300Y143000D03*
X355447Y146528D03*
X344500Y141700D03*
X348675Y143326D03*
X348743Y146072D03*
X346000Y146043D03*
X346450Y149120D03*
X348432Y164844D03*
X346944Y156775D03*
X350550Y153280D03*
X344300Y153800D03*
X344090Y156690D03*
X352000Y162000D03*
X348700Y161700D03*
X351600Y164300D03*
X355400Y152900D03*
X350700Y155600D03*
X345900Y161700D03*
X342188Y183361D03*
X347200Y174300D03*
X344165Y169466D03*
X352200Y171800D03*
X347500Y169500D03*
X351600Y169600D03*
X353302Y182993D03*
X342233Y185639D03*
X356900Y186100D03*
X349600Y194800D03*
X342339Y192225D03*
X342342Y190024D03*
X349100Y191900D03*
X353625Y195045D03*
Y192045D03*
X356600Y195700D03*
X356700Y193300D03*
X345503Y193474D03*
X345500Y190500D03*
X349100Y189700D03*
X353342Y186124D03*
X345500Y184500D03*
X345631Y187420D03*
X353594Y210707D03*
X347593Y210277D03*
X353385Y212898D03*
X343242Y213690D03*
X347664Y212476D03*
X343198Y215910D03*
X371900Y85400D03*
X364800Y91200D03*
X368600Y90700D03*
X361200Y90200D03*
X371950Y92500D03*
X364874Y98250D03*
X362803Y106035D03*
X357900Y99200D03*
X368600Y97500D03*
X357721Y91779D03*
X361200Y97500D03*
X365316Y108130D03*
X372700Y119663D03*
X370100Y119563D03*
X370000Y116563D03*
X362111Y127142D03*
X362120Y124153D03*
X359421Y127128D03*
Y124008D03*
X372821Y125628D03*
X370121Y125528D03*
X367321Y122528D03*
X368026Y137118D03*
X364700Y134000D03*
X367992Y133982D03*
X359300Y130000D03*
X367900Y152550D03*
X368000Y146500D03*
X361700Y143300D03*
X364886Y140268D03*
X368026D03*
Y143418D03*
X364621Y143328D03*
X361500Y149500D03*
X368026Y149718D03*
X358477Y159300D03*
X361600Y159250D03*
X368100Y162200D03*
X358500Y155700D03*
X371100Y168700D03*
X364600Y174800D03*
X361500Y175000D03*
Y168500D03*
X368000D03*
X367906Y171458D03*
X364600Y171600D03*
X364607Y177103D03*
X370900Y171700D03*
X361200Y178500D03*
X372400Y179100D03*
X369021Y180128D03*
X372600Y181400D03*
X368455Y196455D03*
X371299Y196008D03*
X364792Y188743D03*
X364600Y186138D03*
X364895Y190941D03*
X369106Y191903D03*
X369200Y189100D03*
X361257Y193524D03*
Y190700D03*
X364947Y193141D03*
X369009Y186191D03*
X372700Y213700D03*
X369450Y212040D03*
X358498Y210220D03*
X358382Y212427D03*
X371100Y199500D03*
X365250Y208600D03*
X372800Y221600D03*
X369580Y218800D03*
Y215400D03*
X357966Y217516D03*
X359827Y216341D03*
X383350Y83350D03*
X383450Y90500D03*
X387200D03*
X387100Y83500D03*
X375800D03*
Y90500D03*
X379500Y83302D03*
Y90600D03*
X381600Y119900D03*
X381900Y113000D03*
X382596Y108600D03*
X385600Y116500D03*
X385200Y113137D03*
X385721Y119528D03*
X386561Y108812D03*
X385479Y125569D03*
X381500Y123200D03*
X381600Y126427D03*
X385523Y122532D03*
X386708Y137118D03*
X383567Y137096D03*
X380475Y137016D03*
X380443Y130102D03*
X374200Y136994D03*
X380398Y146568D03*
X383548D03*
X374200Y140144D03*
X380400Y152700D03*
X383575Y149603D03*
X380522Y149564D03*
X386853Y149640D03*
X377476Y149688D03*
X374200Y149494D03*
X374100Y159150D03*
X386777Y159005D03*
X380500Y162025D03*
X383700Y162199D03*
X383500Y159000D03*
X374300Y155800D03*
X377500Y165240D03*
X384740Y180080D03*
X381720Y180220D03*
X381800Y183300D03*
X380540Y177370D03*
X380500Y168500D03*
X383693Y171424D03*
X383548Y168390D03*
X386600Y174900D03*
X380477Y171605D03*
X376830Y175640D03*
X376800Y178600D03*
X384650Y183170D03*
X376742Y181524D03*
X381460Y195610D03*
X384390Y196470D03*
X381140Y187960D03*
X381280Y191550D03*
X384708Y188910D03*
X384600Y186100D03*
X376800Y193500D03*
X376900Y196600D03*
X380510Y185500D03*
X384684Y191950D03*
X373922Y193103D03*
X374000Y190350D03*
X379750Y213500D03*
X376300Y211000D03*
Y213700D03*
X384810Y208530D03*
X384644Y205994D03*
X382471Y199843D03*
X382600Y222600D03*
X382750Y229000D03*
X379700Y219200D03*
X385947Y226500D03*
X385900Y218400D03*
X376300Y216200D03*
X385900Y222600D03*
X382700Y226000D03*
X379700Y216500D03*
X372950Y217400D03*
X390700Y89300D03*
X403726Y83826D03*
X403700Y90200D03*
X397300Y89168D03*
X400400Y92200D03*
Y98500D03*
X390750Y96500D03*
X394100Y91400D03*
Y99000D03*
X397100Y96600D03*
X397300Y93100D03*
X392382Y102149D03*
X390650Y93000D03*
X394100Y94900D03*
X400400Y95000D03*
X393331Y118043D03*
X393351Y115107D03*
X397650Y115500D03*
X401749Y112418D03*
X401159Y119636D03*
X401353Y116562D03*
X396276Y120948D03*
X396251Y117999D03*
X396600Y112463D03*
X390683Y108042D03*
X400700Y108800D03*
X389700Y112363D03*
X398500Y125604D03*
X398512Y122815D03*
X401500Y125600D03*
X393482Y123982D03*
X396700Y128000D03*
X389914Y124536D03*
X390100Y127600D03*
X390205Y133858D03*
X392998Y133968D03*
X396148D03*
X396321Y136987D03*
X402561Y137000D03*
X399298Y137118D03*
X392998D03*
X389848D03*
X402400Y140163D03*
X393000Y152663D03*
X402900Y149663D03*
X396148Y140268D03*
X399298D03*
X389848Y146568D03*
X393204Y146436D03*
X403080Y146931D03*
X399198Y146468D03*
X396192Y146444D03*
X392998Y149718D03*
X399198Y149618D03*
X396182Y149674D03*
X396200Y152763D03*
X396300Y162100D03*
X399300Y152863D03*
Y155963D03*
X393028Y162059D03*
X393198Y158940D03*
X403078Y152922D03*
X402373Y155952D03*
X399298Y162090D03*
X402505Y159133D03*
X396148Y158940D03*
X399298D03*
X392599Y181686D03*
X400252Y182966D03*
X403600Y182400D03*
Y180200D03*
X402540Y171760D03*
X402600Y174611D03*
X395573Y175400D03*
X396000Y179000D03*
X393077Y168455D03*
X399385Y171686D03*
X396225D03*
X390025Y174672D03*
X393085Y171686D03*
Y174836D03*
X397100Y181000D03*
X400301Y186099D03*
X397805Y192061D03*
X392600Y190600D03*
X396200Y194700D03*
X392624Y184537D03*
X389500Y193600D03*
X397307Y186607D03*
X395600Y184100D03*
Y190300D03*
X392700Y193563D03*
X403022Y192094D03*
X402967Y195005D03*
X389484Y190442D03*
X389300Y187700D03*
X392100Y213700D03*
X395700Y213600D03*
X400400Y209400D03*
X398500Y208000D03*
X389100Y224000D03*
X399700Y225000D03*
Y216400D03*
X395600Y224400D03*
X395700Y217000D03*
X391950Y220800D03*
X389200Y227400D03*
X392000Y217200D03*
X395700Y220600D03*
X399800D03*
X389150Y230300D03*
X407500Y84000D03*
X407400Y91000D03*
X411300Y85600D03*
X414722Y90250D03*
X414300Y85600D03*
X403800Y87000D03*
X407400Y87400D03*
X411000Y88900D03*
X418300Y91300D03*
X418400Y98150D03*
X411000Y92100D03*
X414622Y98000D03*
X414672Y94500D03*
X417800Y100400D03*
X412650Y100197D03*
X418300Y94800D03*
X407550Y100196D03*
X404529Y118507D03*
X405900Y121700D03*
X409110Y114910D03*
X405200Y115343D03*
X412462Y115713D03*
X409196Y118195D03*
X416904Y119591D03*
X413100Y121800D03*
X404900Y124600D03*
X416000Y135983D03*
X415000Y131400D03*
X408956Y130064D03*
X418500Y128200D03*
X415100Y127900D03*
X406200Y127400D03*
X416851Y122600D03*
X412462Y126300D03*
X405500Y131063D03*
X414900Y147000D03*
X417900Y146900D03*
X408800Y147000D03*
X411900Y146800D03*
X413300Y139100D03*
X413400Y142700D03*
X418000Y142500D03*
X406000Y150200D03*
X407500Y152100D03*
X410400Y152000D03*
X418439Y167118D03*
X414800Y162600D03*
X411800Y162700D03*
X414572Y165913D03*
X411356Y165732D03*
X407500Y157600D03*
X412900Y157800D03*
X407400Y154863D03*
X406100Y159500D03*
X415100Y158100D03*
X410272Y154794D03*
X416400Y155000D03*
X408600Y159600D03*
X411600D03*
X409300Y167163D03*
X404558Y154835D03*
X407100Y167429D03*
X418600Y182800D03*
X414960Y178130D03*
X414950Y181460D03*
X411260Y178090D03*
X411553Y181222D03*
X416400Y170300D03*
X413265Y170423D03*
X410620Y173300D03*
X408158Y178666D03*
X417900Y178363D03*
X415992Y189254D03*
Y186205D03*
X419097Y189563D03*
X416500Y195563D03*
X408242Y184624D03*
X405231Y184976D03*
X408200Y190500D03*
X408100Y193600D03*
X412500Y197300D03*
X405000Y190700D03*
X412100Y190400D03*
X411342Y185024D03*
X405800Y196700D03*
X412200Y192600D03*
X416900Y200100D03*
X416353Y207249D03*
X408200Y226900D03*
X408100Y220500D03*
X404400Y228600D03*
Y222300D03*
X415600Y222700D03*
X415800Y215900D03*
X412050Y225100D03*
X412100Y218400D03*
X408200Y223800D03*
X412000Y222000D03*
X415700Y219200D03*
X404400Y225300D03*
X422078Y97678D03*
X422000Y91300D03*
X427560Y104770D03*
X429105Y106337D03*
X429500Y93800D03*
X434021Y100128D03*
X422050Y94800D03*
X428100Y120000D03*
X424900Y121213D03*
X420600Y118300D03*
X420672Y120600D03*
X422042Y115224D03*
X424700Y115000D03*
X427900Y114300D03*
X428100Y116500D03*
X430302Y112098D03*
X419596Y113463D03*
X428255Y126236D03*
X425000Y135350D03*
X419500Y136400D03*
X430100Y131500D03*
X431700Y128300D03*
X423500Y128200D03*
X427000Y128050D03*
X423900Y131500D03*
X420942Y131324D03*
X431504Y126061D03*
X424982Y126500D03*
X427600Y143841D03*
X421500Y142400D03*
X426900Y147100D03*
X431100Y145500D03*
X424856Y142270D03*
X422400Y139000D03*
X420861Y149687D03*
Y146923D03*
X430694Y142275D03*
X428390Y139059D03*
X423945Y165221D03*
X421710Y167230D03*
X431130Y166660D03*
X428238Y167709D03*
X420804Y162659D03*
X420900Y160037D03*
X425500Y154737D03*
X428400D03*
X434500Y160037D03*
X430360Y181350D03*
X430340Y177620D03*
X423642Y181374D03*
X426970Y178310D03*
X425400Y170240D03*
X428500Y173120D03*
X422337Y170575D03*
X425427Y173113D03*
X419453Y173187D03*
X420922Y178117D03*
X423842Y178274D03*
X428431Y170264D03*
X432100Y190400D03*
X429100Y189696D03*
X426173Y190784D03*
X428830Y195379D03*
X422152Y189600D03*
X420800Y193100D03*
X421171Y196496D03*
X431270Y193425D03*
X425500Y186045D03*
X429933Y197283D03*
X420975Y211300D03*
X427900Y202800D03*
X424832Y200174D03*
X421811Y202603D03*
X421253Y199822D03*
X425642Y209524D03*
X419550Y222700D03*
X419600Y216200D03*
Y219200D03*
X444578Y106201D03*
X442378Y106198D03*
X440178Y106200D03*
X437400Y121600D03*
X442842Y120824D03*
X438700Y112900D03*
X438500Y116400D03*
X439400Y120100D03*
X434960Y114529D03*
X444242Y124324D03*
X435442Y124024D03*
X437800Y128100D03*
X434700Y128200D03*
X443400Y148900D03*
X437472Y152501D03*
X434834Y163817D03*
X439600Y153800D03*
X435105Y181207D03*
X438742Y197224D03*
X435642Y194824D03*
X437921Y192956D03*
X445000Y194500D03*
X443100Y195900D03*
X443000Y192700D03*
X435453Y185397D03*
X436957Y209867D03*
X459800Y118800D03*
X453000Y118700D03*
X456200Y118900D03*
X459700Y129900D03*
X452200Y129800D03*
X463100Y133700D03*
X456000Y133500D03*
X460100Y123100D03*
X453000Y123300D03*
X463200Y126200D03*
X456500Y126100D03*
X461200Y167400D03*
X454200D03*
X464300Y181800D03*
X458000Y171100D03*
X451000D03*
X460000Y174900D03*
X453000D03*
X457400Y197000D03*
X450400D03*
X462500Y189000D03*
X460400Y193300D03*
X453400D03*
X456900D03*
X453900Y197000D03*
X459500Y200700D03*
X452500D03*
X456000D03*
X473900Y178200D03*
X466900D03*
X471300Y181800D03*
X470400Y178200D03*
X467800Y181800D03*
X473100Y185500D03*
X466000D03*
X469500Y189000D03*
X469600Y185500D03*
X466000Y189000D03*
X504000Y12507D03*
X508700Y14607D03*
X511589Y30295D03*
X507839Y30362D03*
X506496Y272500D03*
X523453Y12360D03*
X511800Y12507D03*
X520700Y14807D03*
X518769Y22907D03*
X515484D03*
X525753Y30893D03*
X522733Y32832D03*
X511640Y255956D03*
X514137Y256089D03*
X522908Y255117D03*
X526715Y254700D03*
X511736Y273001D03*
X514900Y271350D03*
X522992Y270700D03*
X525845Y272863D03*
X517846Y262489D03*
X521131D03*
X528525Y12549D03*
X542100Y15107D03*
X530700Y15407D03*
X536485Y22907D03*
X533200D03*
X542407Y30882D03*
X532350Y30807D03*
X529120Y32575D03*
X530015Y255000D03*
X531775Y252231D03*
X541005Y254800D03*
X530900Y273000D03*
X534100Y270700D03*
X541500Y270900D03*
X535562Y262489D03*
X538847D03*
X550000Y12507D03*
X544860Y12407D03*
X552800Y14807D03*
X557745Y22907D03*
X554460D03*
X553079Y30712D03*
X549500Y31607D03*
X545928Y31047D03*
X544800Y255100D03*
X550200Y255500D03*
X551000Y252056D03*
X544292Y273128D03*
X548800Y271000D03*
X551937Y272789D03*
X555641Y262489D03*
X568555Y12407D03*
X561200Y12507D03*
X571600Y14207D03*
X564400Y14307D03*
X570852Y33204D03*
X569800Y29807D03*
X565091Y30815D03*
X561456Y30902D03*
X561419Y254850D03*
X565054Y254773D03*
X568327Y253348D03*
X571867Y254685D03*
X560600Y270300D03*
X564100Y271100D03*
X567800Y270500D03*
X570200Y273100D03*
X558926Y262489D03*
X587940Y12417D03*
X582655Y12407D03*
X579800Y14807D03*
X577824Y22907D03*
X574539D03*
X585179Y30867D03*
X581450Y30707D03*
X587700Y255300D03*
X579205Y254850D03*
X582200Y252206D03*
X587642D03*
X580200Y273000D03*
X582600Y270300D03*
X588036Y273089D03*
X588400Y270300D03*
X573357Y262489D03*
X576642D03*
X594600Y6707D03*
X601704Y22907D03*
X594400Y36207D03*
X589300Y33007D03*
X594600Y260000D03*
X591300Y255010D03*
X590837Y259889D03*
X598398Y260199D03*
X591342Y252206D03*
X594500Y265200D03*
X591500Y270100D03*
X591536Y273000D03*
X590700Y264833D03*
X598300Y265400D03*
X610952Y12307D03*
X616600D03*
X615852Y19807D03*
X615907Y24856D03*
X607300Y14507D03*
X616707Y15616D03*
X604989Y22907D03*
X612000Y17407D03*
X610944Y33333D03*
X607800Y30407D03*
X618900Y33290D03*
X615103Y30690D03*
X619382Y260089D03*
X615532Y259700D03*
X611706Y259387D03*
X606700Y255600D03*
X604074Y254394D03*
X609500Y254900D03*
X609937Y252106D03*
X615537Y264789D03*
X619100Y265300D03*
X611536Y264385D03*
X609896Y272889D03*
X608996Y270206D03*
X605100Y270100D03*
X605065Y272967D03*
X623532Y20007D03*
X623555Y25107D03*
X619607Y19807D03*
X627255Y25107D03*
X627231Y19907D03*
X630955Y25207D03*
X631000Y20107D03*
X634555Y25307D03*
X634757Y20207D03*
X619730Y24864D03*
X630432Y260100D03*
X626682Y260300D03*
X622933Y260189D03*
X634207Y260300D03*
X630455Y265400D03*
X634280Y265332D03*
X626651Y265489D03*
X622899Y265189D03*
X644193Y12907D03*
X648800Y12707D03*
X638400Y20607D03*
X638290Y25674D03*
X642246Y25807D03*
X642451Y20707D03*
X645300Y15507D03*
X648400Y15490D03*
X647000Y29607D03*
X649550Y30807D03*
X643700Y33290D03*
X644100Y30307D03*
X638032Y260342D03*
X642802Y252186D03*
X645920Y254130D03*
X635043Y252106D03*
X638900Y254809D03*
X638090Y265340D03*
X642937Y273089D03*
X646360Y271530D03*
X637288Y270100D03*
X637337Y272944D03*
X648948Y262489D03*
X644550Y267170D03*
X662359Y12379D03*
X659400Y25907D03*
Y20474D03*
X662192Y14874D03*
X663202Y25973D03*
X655602Y25223D03*
X663200Y20956D03*
X655700Y20225D03*
X662503Y33207D03*
X657900Y30690D03*
X664678Y30307D03*
X661708Y30699D03*
X659437Y246389D03*
X665500Y252189D03*
X659500Y274000D03*
X665100Y272700D03*
X652233Y262489D03*
X671290Y12457D03*
X665901Y12307D03*
X674320Y14219D03*
X666175Y14807D03*
X680580Y22807D03*
X677295D03*
X674400Y31307D03*
X671295Y33190D03*
X670200Y254700D03*
X673770Y254752D03*
X669700Y270900D03*
X672800Y272700D03*
X676113Y262489D03*
X679398D03*
X690102Y12502D03*
X684760Y12256D03*
X692200Y15357D03*
X682013Y14848D03*
X695029Y22853D03*
X693300Y30607D03*
X689624Y30383D03*
X685700Y30807D03*
X681900Y30907D03*
X682800Y254900D03*
X685382Y252200D03*
X688800Y254600D03*
X692250Y255700D03*
X682481Y270700D03*
X685100Y273100D03*
X689700Y270800D03*
X692537Y272989D03*
X696192Y262489D03*
X709000Y12407D03*
X702000Y12607D03*
X705031Y14515D03*
X698277Y22855D03*
X708900Y30407D03*
X704430Y33313D03*
X701800Y30807D03*
X701649Y255049D03*
X704178Y252189D03*
X707800Y255000D03*
X711400Y255072D03*
X701300Y270777D03*
X704277Y272989D03*
X709400Y272600D03*
X699477Y262489D03*
X723586Y14080D03*
X712182Y14124D03*
X720100Y14707D03*
X718375Y22907D03*
X715090D03*
X727000Y30407D03*
X723500Y29907D03*
X721747Y32954D03*
X712400Y30807D03*
X721500Y255000D03*
X724374Y254515D03*
X712200Y270500D03*
X722400Y270800D03*
X725300Y272800D03*
X717452Y262489D03*
X720737D03*
X715900Y270000D03*
X742200Y12407D03*
X728010Y12857D03*
X739000Y14407D03*
X731169Y14584D03*
X736091Y23607D03*
X732806D03*
X742100Y33007D03*
X740200Y29907D03*
X730500D03*
X730400Y255400D03*
X732200Y252200D03*
X741560Y255000D03*
X730400Y272850D03*
X732740Y270200D03*
X741200Y270500D03*
X735168Y262489D03*
X738453D03*
X744900Y20500D03*
X745000Y23000D03*
X747441Y33007D03*
X744437Y252189D03*
X744200Y272600D03*
X753000Y272100D03*
G54D17*
X42717Y191732D03*
G54D19*
X144000Y67875D03*
Y147125D03*
X276811Y263386D03*
X296811D03*
X457913Y45276D03*
X477913D03*
G54D14*
X13000Y137000D03*
Y141500D03*
X13100Y150600D03*
X13000Y146000D03*
X45500Y118000D03*
X76200Y187200D03*
X86500Y177500D03*
X90700Y177050D03*
X122250Y228750D03*
Y233000D03*
Y237300D03*
Y241500D03*
X133941Y208863D03*
X131003Y205766D03*
X138100Y208100D03*
X136500Y272500D03*
X158700Y213800D03*
X309100Y206800D03*
X315400Y110800D03*
X311600D03*
X322691Y136023D03*
X323550Y142104D03*
X319401Y149354D03*
X317698Y152311D03*
X315384Y166733D03*
X324953Y161722D03*
X323165Y171937D03*
X324436Y175705D03*
X326399Y169401D03*
X319942Y180524D03*
X320029Y184300D03*
X318700Y207800D03*
X311600Y207600D03*
X328000Y97100D03*
X334850Y96900D03*
X335500Y91600D03*
X339500Y102000D03*
X332600Y101400D03*
X333551Y115090D03*
X333416Y108899D03*
X341309Y135651D03*
X329693Y134428D03*
X331290Y125810D03*
X330870Y130540D03*
X336190Y141970D03*
X330796Y146221D03*
X333742Y161624D03*
X332185Y153806D03*
X334470Y164760D03*
X335400Y169600D03*
X333842Y177224D03*
X332300Y173900D03*
X339875Y177303D03*
X334715Y180900D03*
X329028Y199931D03*
X344523Y98477D03*
X344500Y94000D03*
X347230Y100190D03*
X355175Y108212D03*
X348076Y108910D03*
X354333Y125665D03*
X343000Y124000D03*
X342880Y146180D03*
X350800Y138300D03*
X355342Y143424D03*
X348743Y149100D03*
X342716Y161593D03*
X345562Y178700D03*
X349751Y187241D03*
X356800Y191000D03*
X361141Y104099D03*
X369997Y113706D03*
X358000Y115500D03*
X364600Y137063D03*
X367221Y125428D03*
X370000Y122563D03*
X367121Y128628D03*
X362111Y130128D03*
X361726Y140268D03*
X361700Y146549D03*
X361400Y187600D03*
X361300Y184500D03*
X359750Y208390D03*
X359910Y214100D03*
X377818Y115008D03*
X377800Y124163D03*
X383781Y165235D03*
X393653Y121122D03*
X401500Y122600D03*
X401256Y128755D03*
X397800Y130000D03*
X400352Y180171D03*
X402962Y189014D03*
X397728Y189053D03*
X409110Y120910D03*
X412100Y135600D03*
X412600Y124100D03*
X417753Y131322D03*
X404400Y128900D03*
X415700Y143100D03*
X410302Y141864D03*
X406042Y147025D03*
X415100Y149800D03*
X407399Y142561D03*
X408837Y149809D03*
X413314Y154908D03*
X416315Y183219D03*
X412000Y187500D03*
X405102Y187874D03*
X422300Y126300D03*
X432542Y136898D03*
X426982Y131334D03*
X423496Y144000D03*
X428363Y141756D03*
X426000Y167370D03*
X430542Y160753D03*
X430600Y164513D03*
X422363Y154700D03*
X423966Y190846D03*
X423800Y196500D03*
X433842Y197021D03*
X421848Y186550D03*
X426311Y204399D03*
X443443Y144757D03*
X437398Y146257D03*
X435004Y142110D03*
G54D23*
X305900Y121151D03*
X311200Y114800D03*
X311410Y118110D03*
X312000Y122600D03*
X312917Y133440D03*
X312829Y181940D03*
X345837Y199887D03*
G54D12*
X14000Y104500D03*
X14400Y98000D03*
X14000Y109500D03*
X14500Y198000D03*
X17301Y212401D03*
X4500Y228900D03*
X4600Y223100D03*
X17300Y218307D03*
X10000Y229500D03*
X16400Y224212D03*
X4500Y234800D03*
X4400Y245100D03*
X16118Y230118D03*
X10194Y243106D03*
X9500Y234200D03*
X16899Y241929D03*
X16300Y236023D03*
X4400Y256700D03*
X10190Y258510D03*
X10194Y254917D03*
X10190Y246699D03*
X16899Y247834D03*
Y253740D03*
Y259645D03*
X5000Y275000D03*
X12600Y266900D03*
X7600Y268100D03*
X16899Y265551D03*
X15300Y285800D03*
X4900Y285700D03*
X23400Y81550D03*
X25000Y77300D03*
X32800Y120400D03*
X25800Y120300D03*
X29200D03*
X30000Y196200D03*
X21900Y205400D03*
X31500Y207500D03*
X25200Y286000D03*
X40500Y127700D03*
X38500Y148000D03*
X48500D03*
X41000Y152300D03*
Y143300D03*
X46000D03*
Y152300D03*
X43500Y148000D03*
Y138500D03*
X48500D03*
X38500D03*
X45800Y158100D03*
X34800Y198800D03*
Y203700D03*
X37600Y212700D03*
Y207800D03*
X34500Y216000D03*
X40400Y217100D03*
X40700Y224000D03*
X40200Y238300D03*
Y231300D03*
Y245300D03*
X40500Y260000D03*
X40600Y252500D03*
X52500Y96500D03*
Y106500D03*
X57500Y96500D03*
X60000Y101500D03*
X50000D03*
X55000D03*
X57500Y106500D03*
X60000Y111300D03*
X50000D03*
X55000D03*
X50500Y160000D03*
X54700Y192200D03*
X52700Y184800D03*
X62800Y184300D03*
X57600Y214200D03*
X74000Y37642D03*
X66500D03*
X78300Y64300D03*
X72137Y210237D03*
X79500Y230000D03*
X78700Y259800D03*
X67600Y255800D03*
X66300Y259300D03*
X67000Y263200D03*
X82211Y37747D03*
X89862Y37849D03*
X89400Y58200D03*
X83600Y57600D03*
X95500Y93500D03*
X94000Y137500D03*
Y133000D03*
X84500Y230000D03*
X89500D03*
X84500Y225000D03*
Y235000D03*
X91400Y270300D03*
X92800Y285600D03*
X98500Y37642D03*
X105794Y37692D03*
X104400Y57700D03*
X96800Y53300D03*
X99500Y91500D03*
Y96000D03*
X104000Y92000D03*
Y96500D03*
X105775Y137349D03*
X103175Y134050D03*
X98500Y137500D03*
X109000Y134050D03*
X98500Y133000D03*
X95700Y197200D03*
X99600Y225700D03*
X99328Y235370D03*
X109000Y231400D03*
X97500Y285450D03*
X102000D03*
X106500Y285550D03*
X110700D03*
X113605Y37665D03*
X121500Y37642D03*
X121400Y60100D03*
X114800Y60700D03*
X114500Y134050D03*
X120500Y139000D03*
X125000Y178000D03*
X119760Y191419D03*
X115760D03*
X123760D03*
X129336Y37652D03*
X137300Y37642D03*
X136400Y60600D03*
X130400D03*
X136500Y101523D03*
X136770Y113000D03*
X136500Y126300D03*
X132700Y158600D03*
X153088Y37653D03*
X145070Y37642D03*
X143700Y54503D03*
X154615Y54500D03*
X152811Y84300D03*
X157175Y115462D03*
X150670Y112100D03*
Y122300D03*
X150500Y183000D03*
X157000Y169194D03*
X168791Y37689D03*
X160898Y37704D03*
X169600Y53000D03*
X159957Y51932D03*
X167500Y68000D03*
X158105Y96775D03*
X171800Y126600D03*
X162900Y152200D03*
X167602Y160684D03*
X169800Y181448D03*
X165700Y203400D03*
X162000Y226000D03*
X167000D03*
Y221500D03*
X162000D03*
Y230500D03*
X167000D03*
X162000Y235000D03*
X176640Y37699D03*
X184500Y37700D03*
X185000Y51600D03*
X175758Y52879D03*
X184300Y78500D03*
X177200Y130575D03*
X187597Y133697D03*
X176400Y175700D03*
X185546Y192509D03*
X180546D03*
X175546D03*
X177500Y209500D03*
X176800Y241600D03*
X192400Y37642D03*
X200300D03*
X191700Y52100D03*
X201500Y54500D03*
X196900Y68700D03*
X198500Y83800D03*
X193485Y83724D03*
X202500Y97000D03*
X188363Y116137D03*
X201252Y137766D03*
X192237Y147300D03*
X199900Y154200D03*
X200900Y177000D03*
X202800Y191400D03*
X196000Y186897D03*
X191400Y206100D03*
X203100Y252900D03*
X207600Y37642D03*
X216085Y37649D03*
X210900Y57600D03*
X213558Y98500D03*
X205689Y112879D03*
X205850Y118175D03*
X210100Y135800D03*
X213850Y179850D03*
X205920Y221550D03*
X211900Y253000D03*
X207500D03*
X217000Y252900D03*
X217200Y258000D03*
X223868Y37686D03*
X231780Y37691D03*
X229036Y83000D03*
X231562Y143827D03*
X231611Y138336D03*
X226452Y147300D03*
X233350Y180700D03*
X232225Y193275D03*
X221300Y255400D03*
X239599Y37673D03*
X247500Y37642D03*
X238800Y45300D03*
X240200Y59275D03*
X247500Y60000D03*
X244463Y130655D03*
X242950Y155800D03*
X236477Y179357D03*
X239300Y196800D03*
X236861Y184967D03*
X248300Y213500D03*
X261900Y44900D03*
X255000Y37642D03*
X263100Y37700D03*
X264700Y59400D03*
X256200Y59200D03*
X264189Y98252D03*
X257000Y213500D03*
X252700D03*
X271000Y37800D03*
X278800Y37700D03*
X274000Y55800D03*
X268928Y112625D03*
X268895Y107350D03*
X268300Y141869D03*
X269772Y188274D03*
X274700Y222100D03*
X278200Y281350D03*
X286900Y37800D03*
X294500Y37900D03*
X292500Y60500D03*
X284000Y55800D03*
X288700Y71100D03*
X292100D03*
X295300Y66200D03*
X285100Y129510D03*
X281500Y142100D03*
X295900Y154200D03*
X287700Y211900D03*
X295300Y238100D03*
X282686Y281336D03*
X310348Y37900D03*
X302600Y37800D03*
X302400Y59500D03*
X306100Y90600D03*
X311000Y141731D03*
X297250Y163700D03*
X311242Y158732D03*
X305290Y187836D03*
X301320Y191060D03*
X310500Y195600D03*
X308200D03*
X326096Y37900D03*
X318048Y37700D03*
X311598Y57522D03*
X322548Y58300D03*
X323882Y71643D03*
X318882D03*
X321300Y88200D03*
X325350Y114500D03*
X326313Y122380D03*
X311460Y172078D03*
X323800Y192150D03*
X323789Y188117D03*
X326500Y187900D03*
X311900Y188070D03*
X319500Y212100D03*
X315585Y207787D03*
X324100Y208000D03*
X325200Y221700D03*
X319400Y216200D03*
X313600Y237700D03*
X321400D03*
X333700Y38000D03*
X328300Y58200D03*
X337000Y74202D03*
X328882Y71643D03*
X330470Y112515D03*
X330910Y115010D03*
X338421Y153802D03*
X326831Y196119D03*
X337670Y213520D03*
X332974Y210874D03*
X339800Y207400D03*
X330200Y216800D03*
X336000Y219750D03*
X333036Y231910D03*
X327100Y237100D03*
X353100Y56151D03*
X346600Y121100D03*
X355460Y149510D03*
X355413Y156050D03*
X351700Y167300D03*
X355300Y174600D03*
X350000Y177700D03*
X353321Y180128D03*
X350409Y199755D03*
X354700Y199900D03*
X363583Y37642D03*
X368721Y108528D03*
X365721Y115528D03*
X366400Y112200D03*
X371176Y136890D03*
X364700Y152713D03*
X368100Y165300D03*
X364600D03*
X367950Y159200D03*
X371157Y162320D03*
X371176Y158940D03*
X358342Y165324D03*
X358576Y162090D03*
X361292Y181409D03*
X375400Y37700D03*
X374200Y143294D03*
X386800Y165300D03*
X380398Y165240D03*
X387000Y155850D03*
X393561Y127130D03*
X392998Y165240D03*
X396148Y155790D03*
X393208D03*
X399298Y165240D03*
X395641Y188045D03*
X393000Y236200D03*
X397400Y239700D03*
X389500Y275300D03*
X416922Y116613D03*
X405990Y144251D03*
X409096Y143963D03*
X410100Y157700D03*
X408900Y162463D03*
X410408Y170261D03*
X405100Y178500D03*
X407552Y170424D03*
X405700Y246500D03*
X430500Y17000D03*
X427500Y112091D03*
X425200Y118823D03*
X430342Y119724D03*
X426900Y160040D03*
X419340Y170500D03*
X434482Y177021D03*
X428400Y185900D03*
X423900Y257500D03*
X444783Y28451D03*
X439276Y159645D03*
X443800Y246100D03*
X445300Y274400D03*
X451000Y257413D03*
X456300Y275300D03*
X474000Y9000D03*
X467200Y4400D03*
X480400Y154050D03*
X467100Y154200D03*
X477000Y154050D03*
X470100Y154200D03*
X473500Y154050D03*
X467700Y245500D03*
X481500Y8900D03*
X489600Y8800D03*
X483800Y154050D03*
X487200Y154100D03*
X497100Y8800D03*
X506800Y12907D03*
X508700Y17207D03*
X506500Y32807D03*
X514360Y12417D03*
X526000Y12507D03*
X519426Y12318D03*
X522311Y16720D03*
X514300Y20507D03*
X519623Y20457D03*
X522700Y30007D03*
X513005Y32412D03*
X519400Y33340D03*
X526700Y33207D03*
X524700Y119500D03*
X515000Y119270D03*
X524700Y145041D03*
X537964Y12317D03*
X532500Y13407D03*
X541114Y12307D03*
X528219Y15096D03*
X532472Y20515D03*
X537410Y20584D03*
X529000Y30007D03*
X541950Y33340D03*
X532542Y33307D03*
X537200Y33207D03*
X531000Y228350D03*
X547500Y12507D03*
X553720Y12297D03*
X550234Y14997D03*
X553797Y20496D03*
X549500Y29107D03*
X553250Y33207D03*
X547306Y33134D03*
X552100Y136000D03*
X557100D03*
X558448Y12407D03*
X566040Y12317D03*
X566000Y16507D03*
X572200Y28707D03*
X558500Y20507D03*
X573200Y19907D03*
X565470Y33287D03*
X573242Y32462D03*
X560635Y33264D03*
X572100Y136000D03*
X567100D03*
X562000Y127800D03*
X562100Y136000D03*
X562000Y144900D03*
X573470Y12347D03*
X578620Y12357D03*
X585280Y12267D03*
X583700Y28207D03*
X578600Y20307D03*
X579100Y33207D03*
X585550Y33340D03*
X590000Y14007D03*
X594500Y4007D03*
X600896Y12407D03*
X601000Y20507D03*
X590500Y30507D03*
X594200Y33607D03*
X600360Y33287D03*
X599300Y119270D03*
X588800Y145000D03*
X599200D03*
X598814Y240095D03*
X605700Y12407D03*
X614700Y14107D03*
X610800Y14807D03*
X605728Y20518D03*
X615951Y22356D03*
X610500Y30507D03*
X615044Y33190D03*
X607544Y33340D03*
X618877Y30790D03*
X617700Y125500D03*
X615100Y238900D03*
X633500Y12406D03*
X624000D03*
X634757Y22707D03*
X623480Y22564D03*
X631007Y22707D03*
X619700Y22307D03*
X627257Y22407D03*
X624100Y33190D03*
X633449D03*
X623900Y239600D03*
X641745Y12367D03*
X645200Y27707D03*
X646800Y17607D03*
X642257Y23307D03*
X638507Y23183D03*
X650200Y33307D03*
X641900Y31507D03*
X646000Y46007D03*
X640000D03*
X639500Y136490D03*
X648500Y162600D03*
X657897Y12504D03*
X651316Y12360D03*
X664212Y16356D03*
X663300Y23454D03*
X662916Y28457D03*
X655592Y22723D03*
X659400Y23207D03*
X657900Y33190D03*
X654500Y46107D03*
X653000Y93000D03*
X650726Y125724D03*
X664212Y147993D03*
X661600Y156700D03*
X654100Y221800D03*
X675990Y12357D03*
X669600Y17907D03*
X676600Y20307D03*
X671500Y15007D03*
X671900Y30707D03*
X675970Y33267D03*
X678400Y114500D03*
X668411Y148089D03*
X678500Y141500D03*
X667061Y175239D03*
X676200Y181600D03*
X687602Y12439D03*
X694200Y13507D03*
X681280Y12457D03*
X684500Y15507D03*
X689595Y27883D03*
X685400Y28307D03*
X681700Y20507D03*
X694205Y20302D03*
X693700Y33107D03*
X681280Y33340D03*
X687900Y33327D03*
X693500Y148000D03*
X690000Y159000D03*
X694500D03*
X684700Y179800D03*
X694600Y229800D03*
X699503Y12482D03*
X706360Y12397D03*
X705604Y16949D03*
X710813Y28796D03*
X699104Y20495D03*
X707157Y33333D03*
X700940Y33340D03*
X700089Y91411D03*
X701600Y104900D03*
X701400Y98400D03*
X698000Y181500D03*
X704700Y183800D03*
X710200Y201700D03*
X714000Y12407D03*
X719110Y12347D03*
X725530Y12507D03*
X714100Y20607D03*
X719220Y20553D03*
X721074Y30514D03*
X718350Y33107D03*
X712450Y33340D03*
X725653Y32654D03*
X725632Y49600D03*
X721950Y51950D03*
X722000Y74500D03*
X717000D03*
X715000Y80300D03*
X714500Y85500D03*
X715700Y124200D03*
X727187Y140000D03*
X717000Y187500D03*
X715500Y205837D03*
X737300Y12307D03*
X732110Y12267D03*
X728500Y15507D03*
X742100Y28107D03*
X732000Y20307D03*
X736748D03*
X728500Y27907D03*
X733474Y33340D03*
X738487Y33094D03*
X739500Y75500D03*
X738000Y65700D03*
X738500Y90000D03*
X731340Y82515D03*
X739500Y114900D03*
X741104Y133763D03*
X736900Y162300D03*
X729500D03*
X733400D03*
X737000Y188315D03*
X734000Y205000D03*
X745100Y12256D03*
X744800Y33007D03*
X752500Y49007D03*
X756000Y106000D03*
X758176Y135024D03*
X745104Y129763D03*
X749104Y133763D03*
X745104D03*
X752191Y146613D03*
X745104Y137763D03*
X747000Y162000D03*
X750500D03*
X746000Y182300D03*
X764500Y84800D03*
X760400Y88700D03*
X768100Y89000D03*
X761300Y95700D03*
X768500Y114000D03*
X763600Y168000D03*
X764000Y188000D03*
Y197500D03*
Y192810D03*
Y202310D03*
X769500Y234500D03*
X769400Y252700D03*
X785500Y8000D03*
X784000Y31000D03*
X781500Y51000D03*
X777000Y93100D03*
X774300Y102500D03*
X778500D03*
Y107000D03*
X774300D03*
X783000Y113000D03*
Y118500D03*
Y123000D03*
X779000Y142000D03*
X788515Y144060D03*
X784515D03*
X796515D03*
X792515D03*
X800515D03*
Y148060D03*
X796515D03*
X792515D03*
X810500Y196500D03*
Y192300D03*
X809200Y209500D03*
Y213700D03*
Y218400D03*
X809100Y228600D03*
Y224400D03*
X808700Y238300D03*
Y234100D03*
Y242900D03*
X809500Y251500D03*
Y257000D03*
X808700Y247100D03*
X809700Y285900D03*
X820500Y6500D03*
X821900Y273100D03*
X821600Y285500D03*
G54D29*
X350197Y231103D03*
G54D11*
X11500Y68500D03*
X12000Y279000D03*
X816000Y280000D03*
G54D16*
X45669Y77185D03*
Y172460D03*
G54D21*
X200197Y282677D03*
X298622D03*
G54D10*
X-19686Y15748D03*
Y573228D03*
X846455Y15748D03*
Y573228D03*
G54D25*
X315613Y100850D03*
X339280Y127380D03*
X431188Y116105D03*
X434700Y131800D03*
G54D26*
X325300Y112300D03*
X319252Y140949D03*
X324200Y157800D03*
X311417Y153821D03*
X341300Y169600D03*
X332100Y185600D03*
X338000Y185700D03*
X335000Y185500D03*
X332800Y187700D03*
X358500Y137000D03*
X385750Y128517D03*
X380400Y133928D03*
X387000Y143280D03*
X380398Y143418D03*
X383395Y143306D03*
X399452Y133964D03*
X389380Y130100D03*
X389721Y143320D03*
X393000Y140268D03*
X403132Y144374D03*
X431620Y154620D03*
X421697Y174049D03*
X439275Y124197D03*
X456200Y129600D03*
X459700Y133600D03*
X459800Y126200D03*
X456500Y123000D03*
X457700Y167400D03*
X456500Y174900D03*
X454500Y171100D03*
G54D27*
X322010Y118573D03*
X323007Y127672D03*
X338048Y196250D03*
X342029Y196427D03*
X349600Y126700D03*
X342760Y187810D03*
X371900Y89000D03*
X368600Y94100D03*
X365000Y94700D03*
X357721Y95100D03*
X360900Y94200D03*
X359942Y110924D03*
X375800Y87000D03*
X383450Y86900D03*
X387200D03*
X379500D03*
X379526Y106396D03*
X381950Y100950D03*
X381550Y117400D03*
X377800Y112063D03*
X377713Y121061D03*
X386777Y162155D03*
X377500Y156000D03*
X399300Y168400D03*
X392596Y187541D03*
X417785Y162622D03*
X406000Y162663D03*
X412500Y194900D03*
X418800Y196700D03*
X416139Y192007D03*
X426800Y97850D03*
X419499Y139064D03*
X423910Y175700D03*
X432712Y172469D03*
X435453Y167560D03*
X507817Y252248D03*
X511200Y258900D03*
X509244Y272796D03*
X516600Y252200D03*
X521800Y252875D03*
X513776Y258563D03*
X516727Y273122D03*
X521790Y273140D03*
X517100Y265100D03*
X521987D03*
X532900Y255300D03*
X535098Y252600D03*
X540900Y252300D03*
X527400Y252100D03*
X529300Y271000D03*
X528330Y273140D03*
X539937Y272989D03*
X539505Y265100D03*
X534905Y273097D03*
X534700Y265100D03*
X552800Y255300D03*
X545500Y252600D03*
X553485Y252332D03*
X546200Y271000D03*
X554500Y264900D03*
X546900Y273100D03*
X554434Y272914D03*
X560555Y252503D03*
X563376Y256627D03*
X566151Y252115D03*
X572150Y252200D03*
X570200Y269700D03*
X559600Y272900D03*
X572155Y264900D03*
X565700Y273050D03*
X559700Y264900D03*
X572700Y273100D03*
X582300Y254900D03*
X578800Y252200D03*
X577450Y264900D03*
X580107Y270501D03*
X577636Y272947D03*
X603187Y252056D03*
X589500Y257100D03*
X589900Y268133D03*
X602450Y272900D03*
X598418Y262699D03*
X590322Y262361D03*
X594559Y262559D03*
X595386Y272932D03*
X608700Y257300D03*
X611845Y253723D03*
X611593Y261885D03*
X606200Y267800D03*
X615430Y262213D03*
X612393Y273026D03*
X619180Y262689D03*
X629937Y272990D03*
X630457Y262832D03*
X626680Y262989D03*
X634280Y262832D03*
X620437Y272990D03*
X622930Y262689D03*
X643020Y254710D03*
X647800Y252300D03*
X635197Y254602D03*
X638893Y252206D03*
X644090Y270420D03*
X648200Y265300D03*
X637987Y262842D03*
X639500Y268800D03*
X648291Y273140D03*
X665300Y254700D03*
X661200Y248500D03*
X653600Y252130D03*
X664500Y270000D03*
X653000Y264900D03*
X661600Y272300D03*
X653041Y272989D03*
X669930Y252150D03*
X674636Y252406D03*
X680600Y265000D03*
X675400D03*
X668000Y272890D03*
X680400Y273100D03*
X675400D03*
X690000Y256800D03*
X685390Y254900D03*
X688720Y252090D03*
X693860Y252210D03*
X681900Y252500D03*
X691900Y269300D03*
X683100Y268000D03*
X695500Y265000D03*
Y273100D03*
X687682Y272889D03*
X704137Y254796D03*
X699800Y252230D03*
X701704Y257549D03*
X707490Y252310D03*
X706000Y270500D03*
X700200Y264900D03*
X700300Y273100D03*
X706900Y273000D03*
X712350Y252640D03*
X725950Y252573D03*
X721395Y252175D03*
X721600Y257500D03*
X716737Y252189D03*
X716795Y265000D03*
X721400D03*
X721395Y273100D03*
X713100Y273000D03*
X716737Y272989D03*
X730300Y257900D03*
X734937Y253100D03*
X739750Y252800D03*
X729860Y269810D03*
X734200Y265100D03*
X739111Y264962D03*
X739838Y272813D03*
X727800Y272800D03*
X734510Y273110D03*
X744100Y254800D03*
X749000Y252200D03*
X746737Y272889D03*
G54D28*
X320321Y130528D03*
X351342Y114158D03*
X351000Y111700D03*
X351950Y214800D03*
X346500Y208350D03*
X345500Y213000D03*
X353792Y208466D03*
X355860Y216690D03*
X345300Y216700D03*
X359222Y197700D03*
%LPC*%
G75*
G54D30*
G01X10636Y-27865D02*
G02I-12000J0D01*
G01X14636D02*
X-17364D01*
G01X5486D02*
G02I-6850J0D01*
G01X-1364Y-43865D02*
Y-11865D01*
G01X14636Y-43865D02*
Y-123865D01*
G01D02*
X1309236D01*
G01X14636Y-79365D02*
X1309236D01*
G01X14636Y-43865D02*
X1309236D01*
G01X521736D02*
Y-123865D01*
G01X659236Y-43865D02*
Y-123865D01*
G01X774236Y-43865D02*
Y-123865D01*
G01X941736Y-43865D02*
Y-123865D01*
G01X1111736Y-43865D02*
Y-123865D01*
G01X1309236Y-43865D02*
Y-123865D01*
G01X1341236Y-27865D02*
X1309236D01*
G01X1337236D02*
G02I-12000J0D01*
G01X1332086D02*
G02I-6850J0D01*
G01X1325236Y-43865D02*
Y-11865D01*
G54D31*
G01X70851Y-113865D02*
Y-96365D01*
G01X80021D02*
Y-113865D01*
G01Y-105115D02*
X70851D01*
G01X92936Y-113865D02*
X91626Y-113573D01*
X90316Y-112407D01*
X89442Y-110365D01*
X89006Y-108032D01*
X89442Y-105698D01*
X90316Y-103657D01*
X91626Y-102490D01*
X92936Y-102199D01*
X94246Y-102490D01*
X95556Y-103657D01*
X96429Y-105698D01*
X96648Y-108032D01*
X96429Y-110365D01*
X95556Y-112407D01*
X94246Y-113573D01*
X92936Y-113865D01*
G01X106724D02*
Y-102199D01*
G01Y-105115D02*
X107598Y-103657D01*
X108908Y-102490D01*
X110654Y-102199D01*
X112182Y-102490D01*
X113493Y-103657D01*
X114148Y-105698D01*
Y-113865D01*
G01X124661Y-105990D02*
X131648D01*
X130993Y-103948D01*
X129901Y-102782D01*
X128373Y-102199D01*
X126844Y-102490D01*
X125534Y-103365D01*
X124661Y-105407D01*
X124224Y-107157D01*
Y-108907D01*
X124661Y-110657D01*
X125753Y-112407D01*
X127063Y-113573D01*
X128591Y-113865D01*
X130119Y-113282D01*
X131648Y-111532D01*
G01X140851Y-119115D02*
X142161Y-119698D01*
X143908Y-119115D01*
X144999Y-117949D01*
X145873Y-116490D01*
X147182Y-111824D01*
X150021Y-102199D01*
G01X143034D02*
X147182Y-111824D01*
G01X182182Y-104532D02*
X183056Y-103657D01*
X183711Y-102199D01*
X184148Y-100156D01*
X183711Y-98407D01*
X182838Y-97240D01*
X181309Y-96365D01*
X175414D01*
Y-113865D01*
X182619D01*
X184148Y-112699D01*
X185021Y-110948D01*
X185458Y-108907D01*
X185021Y-106865D01*
X183711Y-105115D01*
X182182Y-104532D01*
X175414D01*
G01X201866Y-113865D02*
Y-102199D01*
G01Y-104240D02*
X200993Y-103074D01*
X199682Y-102490D01*
X198154Y-102199D01*
X196626Y-102782D01*
X195316Y-103948D01*
X194442Y-105698D01*
X194006Y-108032D01*
X194442Y-110365D01*
X195316Y-112115D01*
X196626Y-113282D01*
X198154Y-113865D01*
X199682Y-113573D01*
X200993Y-112699D01*
X201866Y-111532D01*
G01X219366Y-96365D02*
Y-113865D01*
G01Y-111241D02*
X218493Y-112699D01*
X217182Y-113573D01*
X215654Y-113865D01*
X213908Y-113282D01*
X212598Y-111824D01*
X211724Y-110074D01*
X211506Y-108032D01*
X211724Y-105990D01*
X212598Y-104240D01*
X213908Y-102782D01*
X215654Y-102199D01*
X217182Y-102490D01*
X218274Y-103074D01*
X219366Y-104240D01*
G01X229879Y-118240D02*
X231408Y-119407D01*
X233154Y-119698D01*
X234682Y-119407D01*
X235993Y-117949D01*
X236866Y-115907D01*
Y-102199D01*
G01Y-104532D02*
X235993Y-103365D01*
X234682Y-102490D01*
X233154Y-102199D01*
X231408Y-102782D01*
X230316Y-103948D01*
X229442Y-105990D01*
X229006Y-108032D01*
X229224Y-109782D01*
X230098Y-111824D01*
X231408Y-113282D01*
X233154Y-113865D01*
X234464Y-113573D01*
X235993Y-112407D01*
X236866Y-111241D01*
G01X247161Y-105990D02*
X254148D01*
X253493Y-103948D01*
X252401Y-102782D01*
X250873Y-102199D01*
X249344Y-102490D01*
X248034Y-103365D01*
X247161Y-105407D01*
X246724Y-107157D01*
Y-108907D01*
X247161Y-110657D01*
X248253Y-112407D01*
X249563Y-113573D01*
X251091Y-113865D01*
X252619Y-113282D01*
X254148Y-111532D01*
G01X264879Y-113865D02*
Y-102199D01*
G01Y-104532D02*
X265971Y-103365D01*
X267063Y-102490D01*
X268591Y-102199D01*
X269682Y-102490D01*
X270993Y-103365D01*
G01X298569Y-113865D02*
Y-96365D01*
X303809D01*
X305556Y-97240D01*
X306866Y-99282D01*
X307303Y-101615D01*
X306866Y-103948D01*
X305774Y-105698D01*
X303809Y-106574D01*
X298569D01*
G01X324366Y-113865D02*
Y-102199D01*
G01Y-104240D02*
X323493Y-103074D01*
X322182Y-102490D01*
X320654Y-102199D01*
X319126Y-102782D01*
X317816Y-103948D01*
X316942Y-105698D01*
X316506Y-108032D01*
X316942Y-110365D01*
X317816Y-112115D01*
X319126Y-113282D01*
X320654Y-113865D01*
X322182Y-113573D01*
X323493Y-112699D01*
X324366Y-111532D01*
G01X334224Y-113865D02*
Y-102199D01*
G01Y-105115D02*
X335098Y-103657D01*
X336408Y-102490D01*
X338154Y-102199D01*
X339682Y-102490D01*
X340993Y-103657D01*
X341648Y-105698D01*
Y-113865D01*
G01X355436Y-96365D02*
Y-113865D01*
G01X352379Y-102199D02*
X358493D01*
G01X369224Y-113865D02*
Y-96365D01*
G01Y-104823D02*
X370316Y-103365D01*
X371408Y-102490D01*
X373154Y-102199D01*
X374464Y-102490D01*
X375993Y-103657D01*
X376648Y-105407D01*
Y-113865D01*
G01X387161Y-105990D02*
X394148D01*
X393493Y-103948D01*
X392401Y-102782D01*
X390873Y-102199D01*
X389344Y-102490D01*
X388034Y-103365D01*
X387161Y-105407D01*
X386724Y-107157D01*
Y-108907D01*
X387161Y-110657D01*
X388253Y-112407D01*
X389563Y-113573D01*
X391091Y-113865D01*
X392619Y-113282D01*
X394148Y-111532D01*
G01X404879Y-113865D02*
Y-102199D01*
G01Y-104532D02*
X405971Y-103365D01*
X407063Y-102490D01*
X408591Y-102199D01*
X409682Y-102490D01*
X410993Y-103365D01*
G01X437259Y-113865D02*
Y-96365D01*
X442936Y-110948D01*
X448613Y-96365D01*
Y-113865D01*
G01X462182Y-104532D02*
X463056Y-103657D01*
X463711Y-102199D01*
X464148Y-100156D01*
X463711Y-98407D01*
X462838Y-97240D01*
X461309Y-96365D01*
X455414D01*
Y-113865D01*
X462619D01*
X464148Y-112699D01*
X465021Y-110948D01*
X465458Y-108907D01*
X465021Y-106865D01*
X463711Y-105115D01*
X462182Y-104532D01*
X455414D01*
G01X227259Y-68865D02*
Y-51365D01*
X232936Y-65948D01*
X238613Y-51365D01*
Y-68865D01*
G01X250436D02*
X249126Y-68573D01*
X247816Y-67407D01*
X246942Y-65365D01*
X246506Y-63032D01*
X246942Y-60698D01*
X247816Y-58657D01*
X249126Y-57490D01*
X250436Y-57199D01*
X251746Y-57490D01*
X253056Y-58657D01*
X253929Y-60698D01*
X254148Y-63032D01*
X253929Y-65365D01*
X253056Y-67407D01*
X251746Y-68573D01*
X250436Y-68865D01*
G01X271866Y-51365D02*
Y-68865D01*
G01Y-66241D02*
X270993Y-67699D01*
X269682Y-68573D01*
X268154Y-68865D01*
X266408Y-68282D01*
X265098Y-66824D01*
X264224Y-65074D01*
X264006Y-63032D01*
X264224Y-60990D01*
X265098Y-59240D01*
X266408Y-57782D01*
X268154Y-57199D01*
X269682Y-57490D01*
X270774Y-58074D01*
X271866Y-59240D01*
G01X282161Y-60990D02*
X289148D01*
X288493Y-58948D01*
X287401Y-57782D01*
X285873Y-57199D01*
X284344Y-57490D01*
X283034Y-58365D01*
X282161Y-60407D01*
X281724Y-62157D01*
Y-63907D01*
X282161Y-65657D01*
X283253Y-67407D01*
X284563Y-68573D01*
X286091Y-68865D01*
X287619Y-68282D01*
X289148Y-66532D01*
G01X302936Y-68865D02*
Y-51365D01*
G01X542319Y-68865D02*
Y-51365D01*
X547559D01*
X549306Y-52240D01*
X550616Y-54282D01*
X551053Y-56615D01*
X550616Y-58948D01*
X549524Y-60698D01*
X547559Y-61574D01*
X542319D01*
G01X568989Y-52824D02*
X567679Y-51948D01*
X566151Y-51365D01*
X564404D01*
X562439Y-52240D01*
X560911Y-53698D01*
X559819Y-55449D01*
X558946Y-58365D01*
X558727Y-60990D01*
X559164Y-63615D01*
X559819Y-65365D01*
X561129Y-67115D01*
X562658Y-68282D01*
X564186Y-68865D01*
X565714D01*
X567243Y-68282D01*
X568553Y-67407D01*
X569645Y-66241D01*
G01X583432Y-59532D02*
X584306Y-58657D01*
X584961Y-57199D01*
X585398Y-55156D01*
X584961Y-53407D01*
X584088Y-52240D01*
X582559Y-51365D01*
X576664D01*
Y-68865D01*
X583869D01*
X585398Y-67699D01*
X586271Y-65948D01*
X586708Y-63907D01*
X586271Y-61865D01*
X584961Y-60115D01*
X583432Y-59532D01*
X576664D01*
G01X592636Y-74698D02*
X605736D01*
G01X611664Y-68865D02*
Y-51365D01*
X621708Y-68865D01*
Y-51365D01*
G01X634186Y-68865D02*
X632439Y-68573D01*
X630911Y-67407D01*
X629601Y-65657D01*
X628727Y-63615D01*
X628291Y-61282D01*
Y-58948D01*
X628727Y-56615D01*
X629601Y-54573D01*
X630911Y-52824D01*
X632439Y-51657D01*
X634186Y-51365D01*
X635932Y-51657D01*
X637461Y-52824D01*
X638771Y-54573D01*
X639645Y-56615D01*
X640081Y-58948D01*
Y-61282D01*
X639645Y-63615D01*
X638771Y-65657D01*
X637461Y-67407D01*
X635932Y-68573D01*
X634186Y-68865D01*
G01X555436Y-113865D02*
Y-96365D01*
X552816Y-99865D01*
G01Y-113865D02*
X558056D01*
G01X568133Y-110365D02*
X569442Y-112407D01*
X571189Y-113573D01*
X573154Y-113865D01*
X574901Y-113573D01*
X576648Y-112115D01*
X577739Y-110365D01*
X577958Y-108615D01*
X577521Y-106574D01*
X575993Y-105115D01*
X574464Y-104532D01*
X572499D01*
G01X574464D02*
X575774Y-103657D01*
X576866Y-102199D01*
X577303Y-100449D01*
X576866Y-98698D01*
X575774Y-97240D01*
X573809Y-96365D01*
X571844Y-96657D01*
X569879Y-97824D01*
G01X590436Y-113865D02*
Y-96365D01*
X587816Y-99865D01*
G01Y-113865D02*
X593056D01*
G01X603133Y-110365D02*
X604442Y-112407D01*
X606189Y-113573D01*
X608154Y-113865D01*
X609901Y-113573D01*
X611648Y-112115D01*
X612739Y-110365D01*
X612958Y-108615D01*
X612521Y-106574D01*
X610993Y-105115D01*
X609464Y-104532D01*
X607499D01*
G01X609464D02*
X610774Y-103657D01*
X611866Y-102199D01*
X612303Y-100449D01*
X611866Y-98698D01*
X610774Y-97240D01*
X608809Y-96365D01*
X606844Y-96657D01*
X604879Y-97824D01*
G01X625436Y-96365D02*
X623689Y-96948D01*
X622379Y-98407D01*
X621506Y-100156D01*
X620851Y-102490D01*
X620633Y-105115D01*
X620851Y-107740D01*
X621506Y-110074D01*
X622379Y-111824D01*
X623689Y-113282D01*
X625436Y-113865D01*
X627182Y-113282D01*
X628493Y-111824D01*
X629366Y-110074D01*
X630021Y-107740D01*
X630239Y-105115D01*
X630021Y-102490D01*
X629366Y-100156D01*
X628493Y-98407D01*
X627182Y-96948D01*
X625436Y-96365D01*
G01X685027Y-51365D02*
X690486Y-68865D01*
X695945Y-51365D01*
G01X712353Y-68865D02*
X703619D01*
Y-51365D01*
X712353D01*
G01X708859Y-59823D02*
X703619D01*
G01X721119Y-68865D02*
Y-51365D01*
X726578D01*
X728324Y-52240D01*
X729416Y-53407D01*
X729853Y-55740D01*
X729416Y-58074D01*
X728106Y-59532D01*
X726578Y-60407D01*
X721119D01*
G01X726578D02*
X729853Y-68865D01*
G01X742986Y-69448D02*
X742549Y-69157D01*
Y-68573D01*
X742986Y-68282D01*
X743423Y-68573D01*
Y-69157D01*
X742986Y-69448D01*
G01X707986Y-113865D02*
Y-96365D01*
X705366Y-99865D01*
G01Y-113865D02*
X710606D01*
G01X727232Y-104532D02*
X728106Y-103657D01*
X728761Y-102199D01*
X729198Y-100156D01*
X728761Y-98407D01*
X727888Y-97240D01*
X726359Y-96365D01*
X720464D01*
Y-113865D01*
X727669D01*
X729198Y-112699D01*
X730071Y-110948D01*
X730508Y-108907D01*
X730071Y-106865D01*
X728761Y-105115D01*
X727232Y-104532D01*
X720464D01*
G01X906053Y-96365D02*
Y-113865D01*
X897319D01*
G01X884186D02*
Y-96365D01*
X886806Y-99865D01*
G01Y-113865D02*
X881566D01*
G01X866686D02*
Y-96365D01*
X869306Y-99865D01*
G01Y-113865D02*
X864066D01*
G01X847876Y-105115D02*
X843509D01*
Y-110365D01*
X844819Y-112115D01*
X846348Y-113282D01*
X848531Y-113865D01*
X850714Y-113282D01*
X852243Y-112115D01*
X853553Y-110365D01*
X854426Y-108323D01*
X854863Y-105990D01*
Y-103948D01*
X854426Y-102199D01*
X853553Y-100156D01*
X852243Y-98407D01*
X850933Y-97240D01*
X849186Y-96365D01*
X847658D01*
X845911Y-96948D01*
X844601Y-98115D01*
G01X836708Y-113865D02*
Y-96365D01*
X826664Y-113865D01*
Y-96365D01*
G01X818989Y-113865D02*
Y-96365D01*
X814623D01*
X812876Y-97240D01*
X811566Y-98407D01*
X810474Y-100156D01*
X809601Y-102199D01*
X809383Y-105115D01*
X809601Y-108032D01*
X810474Y-110074D01*
X811566Y-111824D01*
X812876Y-112990D01*
X814623Y-113865D01*
X818989D01*
G01X818569Y-51365D02*
Y-68865D01*
X827303D01*
G01X844366D02*
Y-57199D01*
G01Y-59240D02*
X843493Y-58074D01*
X842182Y-57490D01*
X840654Y-57199D01*
X839126Y-57782D01*
X837816Y-58948D01*
X836942Y-60698D01*
X836506Y-63032D01*
X836942Y-65365D01*
X837816Y-67115D01*
X839126Y-68282D01*
X840654Y-68865D01*
X842182Y-68573D01*
X843493Y-67699D01*
X844366Y-66532D01*
G01X853351Y-74115D02*
X854661Y-74698D01*
X856408Y-74115D01*
X857499Y-72949D01*
X858373Y-71490D01*
X859682Y-66824D01*
X862521Y-57199D01*
G01X855534D02*
X859682Y-66824D01*
G01X872161Y-60990D02*
X879148D01*
X878493Y-58948D01*
X877401Y-57782D01*
X875873Y-57199D01*
X874344Y-57490D01*
X873034Y-58365D01*
X872161Y-60407D01*
X871724Y-62157D01*
Y-63907D01*
X872161Y-65657D01*
X873253Y-67407D01*
X874563Y-68573D01*
X876091Y-68865D01*
X877619Y-68282D01*
X879148Y-66532D01*
G01X889879Y-68865D02*
Y-57199D01*
G01Y-59532D02*
X890971Y-58365D01*
X892063Y-57490D01*
X893591Y-57199D01*
X894682Y-57490D01*
X895993Y-58365D01*
G01X943619Y-110365D02*
X944711Y-112115D01*
X946021Y-113282D01*
X947549Y-113865D01*
X949296Y-113282D01*
X950606Y-112115D01*
X951916Y-110365D01*
X952353Y-108032D01*
Y-96365D01*
G01X965486Y-113865D02*
X963739Y-113573D01*
X962211Y-112407D01*
X960901Y-110657D01*
X960027Y-108615D01*
X959591Y-106282D01*
Y-103948D01*
X960027Y-101615D01*
X960901Y-99573D01*
X962211Y-97824D01*
X963739Y-96657D01*
X965486Y-96365D01*
X967232Y-96657D01*
X968761Y-97824D01*
X970071Y-99573D01*
X970945Y-101615D01*
X971381Y-103948D01*
Y-106282D01*
X970945Y-108615D01*
X970071Y-110657D01*
X968761Y-112407D01*
X967232Y-113573D01*
X965486Y-113865D01*
G01X978401Y-111532D02*
X980148Y-112990D01*
X982113Y-113865D01*
X983859D01*
X985606Y-112990D01*
X986916Y-111532D01*
X987571Y-109490D01*
X987134Y-107449D01*
X986043Y-105698D01*
X984078Y-104532D01*
X981458Y-103948D01*
X979929Y-102782D01*
X979274Y-100740D01*
X979711Y-98698D01*
X980803Y-97240D01*
X982331Y-96365D01*
X983859D01*
X985388Y-96948D01*
X986698Y-98407D01*
G01X1004853Y-113865D02*
X996119D01*
Y-96365D01*
X1004853D01*
G01X1001359Y-104823D02*
X996119D01*
G01X1013619Y-113865D02*
Y-96365D01*
X1018859D01*
X1020606Y-97240D01*
X1021916Y-99282D01*
X1022353Y-101615D01*
X1021916Y-103948D01*
X1020824Y-105698D01*
X1018859Y-106574D01*
X1013619D01*
G01X1030901Y-113865D02*
Y-96365D01*
G01X1040071D02*
Y-113865D01*
G01Y-105115D02*
X1030901D01*
G01X1066119Y-96365D02*
Y-113865D01*
X1074853D01*
G01X1082527D02*
X1087986Y-96365D01*
X1093445Y-113865D01*
G01X1091479Y-107740D02*
X1084492D01*
G01X1100683Y-96365D02*
Y-108907D01*
X1101556Y-111532D01*
X1103303Y-113282D01*
X1105486Y-113865D01*
X1107669Y-113282D01*
X1109416Y-111532D01*
X1110289Y-108907D01*
Y-96365D01*
G01X960683Y-68865D02*
Y-51365D01*
X965049D01*
X966796Y-52240D01*
X968106Y-53407D01*
X969198Y-55156D01*
X970071Y-57199D01*
X970289Y-60115D01*
X970071Y-63032D01*
X969198Y-65074D01*
X968106Y-66824D01*
X966796Y-67990D01*
X965049Y-68865D01*
X960683D01*
G01X979711Y-60990D02*
X986698D01*
X986043Y-58948D01*
X984951Y-57782D01*
X983423Y-57199D01*
X981894Y-57490D01*
X980584Y-58365D01*
X979711Y-60407D01*
X979274Y-62157D01*
Y-63907D01*
X979711Y-65657D01*
X980803Y-67407D01*
X982113Y-68573D01*
X983641Y-68865D01*
X985169Y-68282D01*
X986698Y-66532D01*
G01X997211Y-66824D02*
X998303Y-67990D01*
X999831Y-68865D01*
X1001141D01*
X1002451Y-68282D01*
X1003324Y-67407D01*
X1003761Y-66241D01*
X1003543Y-64490D01*
X1002669Y-63615D01*
X998739Y-61865D01*
X997866Y-59823D01*
X998303Y-58365D01*
X999176Y-57490D01*
X1000486Y-57199D01*
X1001796Y-57490D01*
X1003106Y-58365D01*
G01X1017986Y-57199D02*
Y-68865D01*
G01Y-52532D02*
X1017549Y-52240D01*
Y-51657D01*
X1017986Y-51365D01*
X1018423Y-51657D01*
Y-52240D01*
X1017986Y-52532D01*
G01X1032429Y-73240D02*
X1033958Y-74407D01*
X1035704Y-74698D01*
X1037232Y-74407D01*
X1038543Y-72949D01*
X1039416Y-70907D01*
Y-57199D01*
G01Y-59532D02*
X1038543Y-58365D01*
X1037232Y-57490D01*
X1035704Y-57199D01*
X1033958Y-57782D01*
X1032866Y-58948D01*
X1031992Y-60990D01*
X1031556Y-63032D01*
X1031774Y-64782D01*
X1032648Y-66824D01*
X1033958Y-68282D01*
X1035704Y-68865D01*
X1037014Y-68573D01*
X1038543Y-67407D01*
X1039416Y-66241D01*
G01X1049274Y-68865D02*
Y-57199D01*
G01Y-60115D02*
X1050148Y-58657D01*
X1051458Y-57490D01*
X1053204Y-57199D01*
X1054732Y-57490D01*
X1056043Y-58657D01*
X1056698Y-60698D01*
Y-68865D01*
G01X1067211Y-60990D02*
X1074198D01*
X1073543Y-58948D01*
X1072451Y-57782D01*
X1070923Y-57199D01*
X1069394Y-57490D01*
X1068084Y-58365D01*
X1067211Y-60407D01*
X1066774Y-62157D01*
Y-63907D01*
X1067211Y-65657D01*
X1068303Y-67407D01*
X1069613Y-68573D01*
X1071141Y-68865D01*
X1072669Y-68282D01*
X1074198Y-66532D01*
G01X1084929Y-68865D02*
Y-57199D01*
G01Y-59532D02*
X1086021Y-58365D01*
X1087113Y-57490D01*
X1088641Y-57199D01*
X1089732Y-57490D01*
X1091043Y-58365D01*
G01X1131686Y-113865D02*
Y-96365D01*
X1129066Y-99865D01*
G01Y-113865D02*
X1134306D01*
G01X1149186D02*
Y-96365D01*
X1146566Y-99865D01*
G01Y-113865D02*
X1151806D01*
G01X1162756Y-114448D02*
X1170616Y-96365D01*
G01X1184186Y-113865D02*
Y-96365D01*
X1181566Y-99865D01*
G01Y-113865D02*
X1186806D01*
G01X1196883Y-110365D02*
X1198192Y-112407D01*
X1199939Y-113573D01*
X1201904Y-113865D01*
X1203651Y-113573D01*
X1205398Y-112115D01*
X1206489Y-110365D01*
X1206708Y-108615D01*
X1206271Y-106574D01*
X1204743Y-105115D01*
X1203214Y-104532D01*
X1201249D01*
G01X1203214D02*
X1204524Y-103657D01*
X1205616Y-102199D01*
X1206053Y-100449D01*
X1205616Y-98698D01*
X1204524Y-97240D01*
X1202559Y-96365D01*
X1200594Y-96657D01*
X1198629Y-97824D01*
G01X1215256Y-114448D02*
X1223116Y-96365D01*
G01X1232538Y-99282D02*
X1233848Y-97532D01*
X1235376Y-96657D01*
X1237123Y-96365D01*
X1239306Y-96948D01*
X1240834Y-98407D01*
X1241271Y-100156D01*
X1241053Y-101907D01*
X1240179Y-103365D01*
X1235813Y-106282D01*
X1233848Y-108323D01*
X1232538Y-111241D01*
X1232101Y-113865D01*
X1241271D01*
G01X1254186Y-96365D02*
X1252439Y-96948D01*
X1251129Y-98407D01*
X1250256Y-100156D01*
X1249601Y-102490D01*
X1249383Y-105115D01*
X1249601Y-107740D01*
X1250256Y-110074D01*
X1251129Y-111824D01*
X1252439Y-113282D01*
X1254186Y-113865D01*
X1255932Y-113282D01*
X1257243Y-111824D01*
X1258116Y-110074D01*
X1258771Y-107740D01*
X1258989Y-105115D01*
X1258771Y-102490D01*
X1258116Y-100156D01*
X1257243Y-98407D01*
X1255932Y-96948D01*
X1254186Y-96365D01*
G01X1271686Y-113865D02*
Y-96365D01*
X1269066Y-99865D01*
G01Y-113865D02*
X1274306D01*
G01X1291806D02*
Y-96365D01*
X1283727Y-108907D01*
X1294645D01*
G01X1179383Y-68865D02*
Y-51365D01*
X1183749D01*
X1185496Y-52240D01*
X1186806Y-53407D01*
X1187898Y-55156D01*
X1188771Y-57199D01*
X1188989Y-60115D01*
X1188771Y-63032D01*
X1187898Y-65074D01*
X1186806Y-66824D01*
X1185496Y-67990D01*
X1183749Y-68865D01*
X1179383D01*
G01X1205616D02*
Y-57199D01*
G01Y-59240D02*
X1204743Y-58074D01*
X1203432Y-57490D01*
X1201904Y-57199D01*
X1200376Y-57782D01*
X1199066Y-58948D01*
X1198192Y-60698D01*
X1197756Y-63032D01*
X1198192Y-65365D01*
X1199066Y-67115D01*
X1200376Y-68282D01*
X1201904Y-68865D01*
X1203432Y-68573D01*
X1204743Y-67699D01*
X1205616Y-66532D01*
G01X1219186Y-51365D02*
Y-68865D01*
G01X1216129Y-57199D02*
X1222243D01*
G01X1233411Y-60990D02*
X1240398D01*
X1239743Y-58948D01*
X1238651Y-57782D01*
X1237123Y-57199D01*
X1235594Y-57490D01*
X1234284Y-58365D01*
X1233411Y-60407D01*
X1232974Y-62157D01*
Y-63907D01*
X1233411Y-65657D01*
X1234503Y-67407D01*
X1235813Y-68573D01*
X1237341Y-68865D01*
X1238869Y-68282D01*
X1240398Y-66532D01*
M02*
